STUFF LIST - 1  
10M04SAU324I7G-10M04SAU324I7G,A AJ10M040T03              U122            

----------------

74CBTLV3126PW-74CBTLV3126PW,SMA AL003126K08              U17             
74CBTLV3126PW-74CBTLV3126PW,SMA AL003126K08              U18             
74CBTLV3126PW-74CBTLV3126PW,SMA AL003126K08              U67             
74CBTLV3126PW-74CBTLV3126PW,SMA AL003126K08              U68             
74CBTLV3126PW-74CBTLV3126PW,SMA AL003126K08              U86             

----------------

74CBTLV3126PW-74CBTLV3126PW,SMB AL003126K08              U77             

----------------

74HC1G126GW-74HC1G126GW,SMLF,IA AL1G0126007              U66             

----------------

74LVC1G02GW_SMLF-74LVC1G02GW,IA ALVC1G02000              U23             

----------------

74LVC1G07GV-74LVC1G07GV,SMLF,IA AL1G0007001              U54             
74LVC1G07GV-74LVC1G07GV,SMLF,IA AL1G0007001              U104            

----------------

74LVC1G126GW_SMLF-74LVC1G126GWA AL1G0126023              U82             

----------------

9QXL2001BNHGI8-9QXL2001BNHGI8,A AJ020010003              U38             

----------------

9SQ440NQQI8-9SQ440NQQI8,SMLF,IA AJ004400000              U13             

----------------

ADM1086AKSZREEL7-ADM1086AKSZ-RA AL001086001              U94             

----------------

ADS1015IDGSR-ADS1015IDGSR,SMLFA AL001015K00              U105            

----------------

APX80929SAG7-APX809-29SAG-7,SMA AL080929000              U52             

----------------

BAS70057F-BAS70-05-7-F,SMLF,ICA BC0BAS70Z01              U62             

----------------

BAT547F-BAT547F,SMLF,IC,BC0BATA BC0BAT54Z53              D7              

----------------

CONN10_10142708102011LF-CONN10A DFHD10MS383              J49             
CONN10_10142708102011LF-CONN10A DFHD10MS383              J50             

----------------

CONN10_G2100HT0038071-CONN10_GA DFHD10MS268              J43             

----------------

CONN24_52SH90245BRD-CONN24_52SA DFHD24MS090              J44             

----------------

CONN2_AAABAT029P15-CONN2_AAA-BA DFHS02FR031              BT1             

----------------

CONN3_210HP1030BR1-CONN3_210-HA DFHD03MS213              JP1             
CONN3_210HP1030BR1-CONN3_210-HA DFHD03MS213              JP7             

----------------

CONN3_HFK1030G000LAF-CONN3_HFKA DFHD03MS239              JP5             
CONN3_HFK1030G000LAF-CONN3_HFKA DFHD03MS239              JP8             

----------------

CONN56_ME2005602311011-CONN56_A DFHS56FR013              J90             
CONN56_ME2005602311011-CONN56_A DFHS56FR013              J91             
CONN56_ME2005602311011-CONN56_A DFHS56FR013              J92             
CONN56_ME2005602311011-CONN56_A DFHS56FR013              J93             

----------------

CONN7_ABASAT054KA1-CONN7_ABA-SA DFHD07MS215              J54             

----------------

CONN9_2UB3903013101F-CONN9_2UBA DFHS09FS026              J48             

----------------

DELTA_L-DELTA-L,THLF,EMPTY,TP24 TP24                     J63             
DELTA_L-DELTA-L,THLF,EMPTY,TP24 TP24                     J64             
DELTA_L-DELTA-L,THLF,EMPTY,TP24 TP24                     J65             
DELTA_L-DELTA-L,THLF,EMPTY,TP24 TP24                     J66             
DELTA_L-DELTA-L,THLF,EMPTY,TP24 TP24                     J67             
DELTA_L-DELTA-L,THLF,EMPTY,TP24 TP24                     J68             
DELTA_L-DELTA-L,THLF,EMPTY,TP24 TP24                     J69             
DELTA_L-DELTA-L,THLF,EMPTY,TP24 TP24                     J70             
DELTA_L-DELTA-L,THLF,EMPTY,TP24 TP24                     J71             
DELTA_L-DELTA-L,THLF,EMPTY,TP24 TP24                     J72             
DELTA_L-DELTA-L,THLF,EMPTY,TP24 TP24                     J73             
DELTA_L-DELTA-L,THLF,EMPTY,TP24 TP24                     J74             
DELTA_L-DELTA-L,THLF,EMPTY,TP24 TP24                     J75             
DELTA_L-DELTA-L,THLF,EMPTY,TP24 TP24                     J76             
DELTA_L-DELTA-L,THLF,EMPTY,TP24 TP24                     J77             
DELTA_L-DELTA-L,THLF,EMPTY,TP24 TP24                     J78             
DELTA_L-DELTA-L,THLF,EMPTY,TP24 TP24                     J79             
DELTA_L-DELTA-L,THLF,EMPTY,TP24 TP24                     J80             
DELTA_L-DELTA-L,THLF,EMPTY,TP24 TP24                     J81             
DELTA_L-DELTA-L,THLF,EMPTY,TP24 TP24                     J82             
DELTA_L-DELTA-L,THLF,EMPTY,TP24 TP24                     J83             
DELTA_L-DELTA-L,THLF,EMPTY,TP24 TP24                     J84             
DELTA_L-DELTA-L,THLF,EMPTY,TP24 TP24                     J85             
DELTA_L-DELTA-L,THLF,EMPTY,TP24 TP24                     J86             

----------------

DIODE_TVS-SMF14A,SMLF,IC,BCSMFA BCSMF14AZ01              D8              
DIODE_TVS-SMF14A,SMLF,IC,BCSMFA BCSMF14AZ01              D9              
DIODE_TVS-SMF14A,SMLF,IC,BCSMFA BCSMF14AZ01              D10             
DIODE_TVS-SMF14A,SMLF,IC,BCSMFA BCSMF14AZ01              D11             
DIODE_TVS-SMF14A,SMLF,IC,BCSMFA BCSMF14AZ01              D12             

----------------

DUMMY_SYMBOL-BARCODE,MECH,EMPTA DUMMY6                   DM14            
DUMMY_SYMBOL-BARCODE,MECH,EMPTA DUMMY6                   DM15            

----------------

DUMMY_SYMBOL-BATTERY_SYMBOL,MEA DUMMY12                  DM13            

----------------

DUMMY_SYMBOL-EFI BIOS LABEL,MEA DUMMY28_HCLU2002010      DM8             

----------------

DUMMY_SYMBOL-MECHANIC_SYMBOL,MA DUMMY10                  DM9             

----------------

DUMMY_SYMBOL-PB-E1_SMALL,MECH,A DUMMY3                   DM7             

----------------

DUMMY_SYMBOL-PCBA_LABEL_15X5,MA DUMMY4                   DM10            

----------------

DUMMY_SYMBOL-PCB_VENDOR_LOGO_1A DUMMY7                   DM16            

----------------

DUMMY_SYMBOL-QUANTA_LOGO_7X26,A DUMMY1                   ME8             

----------------

DUMMY_SYMBOL-WEEE,MECH,EMPTY,DA DUMMY2                   DM4             

----------------

EMMITSBURG_REV0P9-GFNOCPU04302A AJ0QV2N0T00              U4              

----------------

GTL2014PW-GTL2014PW,SMLF,IC,ALA AL002014K01              U83             
GTL2014PW-GTL2014PW,SMLF,IC,ALA AL002014K01              U84             

----------------

HOLE_TH-EMPTY,DUMMY50 DUMMY50                  H27             
HOLE_TH-EMPTY,DUMMY50 DUMMY50                  H28             
HOLE_TH-EMPTY,DUMMY50 DUMMY50                  H29             
HOLE_TH-EMPTY,DUMMY50 DUMMY50                  H30             

----------------

HOLE_TH-EMPTY,HOLE491 HOLE491                  H33             
HOLE_TH-EMPTY,HOLE491 HOLE491                  H34             

----------------

HOLE_TH-EMPTY,HOLE1068 HOLE1068                 H41             
HOLE_TH-EMPTY,HOLE1068 HOLE1068                 H42             
HOLE_TH-EMPTY,HOLE1068 HOLE1068                 H43             

----------------

HOLE_TH-EMPTY,HOLE1079 HOLE1079                 H15             
HOLE_TH-EMPTY,HOLE1079 HOLE1079                 H16             
HOLE_TH-EMPTY,HOLE1079 HOLE1079                 H17             
HOLE_TH-EMPTY,HOLE1079 HOLE1079                 H18             
HOLE_TH-EMPTY,HOLE1079 HOLE1079                 H19             
HOLE_TH-EMPTY,HOLE1079 HOLE1079                 H20             
HOLE_TH-EMPTY,HOLE1079 HOLE1079                 H21             
HOLE_TH-EMPTY,HOLE1079 HOLE1079                 H22             
HOLE_TH-EMPTY,HOLE1079 HOLE1079                 H23             
HOLE_TH-EMPTY,HOLE1079 HOLE1079                 H24             
HOLE_TH-EMPTY,HOLE1079 HOLE1079                 H25             
HOLE_TH-EMPTY,HOLE1079 HOLE1079                 H26             

----------------

HOLE_TH-EMPTY,HOLE1087 HOLE1087                 H1              
HOLE_TH-EMPTY,HOLE1087 HOLE1087                 H2              
HOLE_TH-EMPTY,HOLE1087 HOLE1087                 H3              
HOLE_TH-EMPTY,HOLE1087 HOLE1087                 H4              
HOLE_TH-EMPTY,HOLE1087 HOLE1087                 H5              
HOLE_TH-EMPTY,HOLE1087 HOLE1087                 H6              
HOLE_TH-EMPTY,HOLE1087 HOLE1087                 H7              
HOLE_TH-EMPTY,HOLE1087 HOLE1087                 H8              
HOLE_TH-EMPTY,HOLE1087 HOLE1087                 H9              
HOLE_TH-EMPTY,HOLE1087 HOLE1087                 H10             
HOLE_TH-EMPTY,HOLE1087 HOLE1087                 H11             
HOLE_TH-EMPTY,HOLE1087 HOLE1087                 H12             
HOLE_TH-EMPTY,HOLE1087 HOLE1087                 H13             
HOLE_TH-EMPTY,HOLE1087 HOLE1087                 H54             
HOLE_TH-EMPTY,HOLE1087 HOLE1087                 H55             

----------------

HOLE_TH-EMPTY,HOLE1098 HOLE1098                 H35             
HOLE_TH-EMPTY,HOLE1098 HOLE1098                 H37             

----------------

HOLE_TH-EMPTY,HOLE1212 HOLE1212                 H44             
HOLE_TH-EMPTY,HOLE1212 HOLE1212                 H45             
HOLE_TH-EMPTY,HOLE1212 HOLE1212                 H47             
HOLE_TH-EMPTY,HOLE1212 HOLE1212                 H49             

----------------

HOLE_TH-EMPTY,HOLE1214 HOLE1214                 H31             
HOLE_TH-EMPTY,HOLE1214 HOLE1214                 H32             

----------------

HOLE_TH-EMPTY,HOLE1222 HOLE1222                 H39             
HOLE_TH-EMPTY,HOLE1222 HOLE1222                 H40             

----------------

HOLE_TH-EMPTY,TMP-Q_HOLE78 TMP-Q_HOLE78             H36             
HOLE_TH-EMPTY,TMP-Q_HOLE78 TMP-Q_HOLE78             H38             

----------------

IDTQS3VH257QG_SMLF-IDTQS3VH257A AL000257W24              U14             
IDTQS3VH257QG_SMLF-IDTQS3VH257A AL000257W24              U15             

----------------

ISL69260IRAZT-ISL69260IRAZ-T,SA AL069260000              PU5             
ISL69260IRAZT-ISL69260IRAZ-T,SA AL069260000              PU18            
ISL69260IRAZT-ISL69260IRAZ-T,SA AL069260000              PU22            
ISL69260IRAZT-ISL69260IRAZ-T,SA AL069260000              PU35            

----------------

ISL99390FRZTR5935-ISL99390FRZ-A AL099390004              PU10_P0_4       
ISL99390FRZTR5935-ISL99390FRZ-A AL099390004              PU11_P0_3       
ISL99390FRZTR5935-ISL99390FRZ-A AL099390004              PU12_P0_2       
ISL99390FRZTR5935-ISL99390FRZ-A AL099390004              PU13_P0_1       
ISL99390FRZTR5935-ISL99390FRZ-A AL099390004              PU23_P1_8       
ISL99390FRZTR5935-ISL99390FRZ-A AL099390004              PU24_P1_7       
ISL99390FRZTR5935-ISL99390FRZ-A AL099390004              PU25_P1_6       
ISL99390FRZTR5935-ISL99390FRZ-A AL099390004              PU26_P1_5       
ISL99390FRZTR5935-ISL99390FRZ-A AL099390004              PU27_P1_4       
ISL99390FRZTR5935-ISL99390FRZ-A AL099390004              PU28_P1_3       
ISL99390FRZTR5935-ISL99390FRZ-A AL099390004              PU30_P1_2       
ISL99390FRZTR5935-ISL99390FRZ-A AL099390004              PU31_P1_1       
ISL99390FRZTR5935-ISL99390FRZ-A AL099390004              PU69_P0_1       
ISL99390FRZTR5935-ISL99390FRZ-A AL099390004              PU6_P0_8        
ISL99390FRZTR5935-ISL99390FRZ-A AL099390004              PU70_P0_2       
ISL99390FRZTR5935-ISL99390FRZ-A AL099390004              PU75_P1_1       
ISL99390FRZTR5935-ISL99390FRZ-A AL099390004              PU76_P1_2       
ISL99390FRZTR5935-ISL99390FRZ-A AL099390004              PU77_P1_3       
ISL99390FRZTR5935-ISL99390FRZ-A AL099390004              PU78_P1_4       
ISL99390FRZTR5935-ISL99390FRZ-A AL099390004              PU7_P0_7        
ISL99390FRZTR5935-ISL99390FRZ-A AL099390004              PU8_P0_6        
ISL99390FRZTR5935-ISL99390FRZ-A AL099390004              PU9_P0_5        

----------------

ISL99390FRZTR5935-ISL99390FRZ-B AL099390004              PU71_P0_3       
ISL99390FRZTR5935-ISL99390FRZ-B AL099390004              PU72_P0_4       

----------------

M24128BWDW6TP-M24128-BWDW6TP,SA AKE30Z0K610              U64             

----------------

MAX11607EUAT-MAX11607EUA+T,SMLA AL011607000              U121            

----------------

MAX9634FEUKT-MAX9634FEUK+T,SMLA AL009634002              U102            
MAX9634FEUKT-MAX9634FEUK+T,SMLA AL009634002              U103            

----------------

ME_DUMMY_SYMBOL-PICKUP_SMDC10,A DUMMY49                  ME5             
ME_DUMMY_SYMBOL-PICKUP_SMDC10,A DUMMY49                  ME6             
ME_DUMMY_SYMBOL-PICKUP_SMDC10,A DUMMY49                  ME7             
ME_DUMMY_SYMBOL-PICKUP_SMDC10,A DUMMY49                  ME16            

----------------

ME_DUMMY_SYMBOL-PICKUP_SMDC20,A DUMMY48                  ME2             
ME_DUMMY_SYMBOL-PICKUP_SMDC20,A DUMMY48                  ME3             
ME_DUMMY_SYMBOL-PICKUP_SMDC20,A DUMMY48                  ME4             
ME_DUMMY_SYMBOL-PICKUP_SMDC20,A DUMMY48                  ME9             
ME_DUMMY_SYMBOL-PICKUP_SMDC20,A DUMMY48                  ME10            
ME_DUMMY_SYMBOL-PICKUP_SMDC20,A DUMMY48                  ME11            
ME_DUMMY_SYMBOL-PICKUP_SMDC20,A DUMMY48                  ME12            
ME_DUMMY_SYMBOL-PICKUP_SMDC20,A DUMMY48                  ME13            
ME_DUMMY_SYMBOL-PICKUP_SMDC20,A DUMMY48                  ME14            
ME_DUMMY_SYMBOL-PICKUP_SMDC20,A DUMMY48                  ME15            

----------------

MOSFET_NCH_1D3S-PSMNR58-30YLH,A BAMNR580000              PQ1             
MOSFET_NCH_1D3S-PSMNR58-30YLH,A BAMNR580000              PQ2             

----------------

MOSFET_NCH_DUAL-2N7002KDW,SMLFA BAM70020047              Q15             
MOSFET_NCH_DUAL-2N7002KDW,SMLFA BAM70020047              Q16             
MOSFET_NCH_DUAL-2N7002KDW,SMLFA BAM70020047              Q37             
MOSFET_NCH_DUAL-2N7002KDW,SMLFA BAM70020047              Q39             
MOSFET_NCH_DUAL-2N7002KDW,SMLFA BAM70020047              Q45             

----------------

MOSFET_N_GSD-NX7002AK,SMLF,IC,A BAM70020062              Q34             
MOSFET_N_GSD-NX7002AK,SMLF,IC,A BAM70020062              Q35             

----------------

MOSFET_N_SMLF-BSS138K,BSS138K,A BAM138K0000              U19             
MOSFET_N_SMLF-BSS138K,BSS138K,A BAM138K0000              U49             
MOSFET_N_SMLF-BSS138K,BSS138K,A BAM138K0000              U70             
MOSFET_N_SMLF-BSS138K,BSS138K,A BAM138K0000              U74             
MOSFET_N_SMLF-BSS138K,BSS138K,A BAM138K0000              U87             
MOSFET_N_SMLF-BSS138K,BSS138K,A BAM138K0000              U89             

----------------

MOSFET_N_SMLF-BSS138K,BSS138K,B BAM138K0000              U73             

----------------

MOSFET_PCH_GDS_ESD_PROTECTED-PA BAM34150008              Q33             

----------------

MP5981GLUZ-MP5981GLU-Z,SMLF,ICA AL005981000              U81             
MP5981GLUZ-MP5981GLU-Z,SMLF,ICA AL005981000              U107            

----------------

MPQ8626GDZ-MPQ8626GD-Z,SMLF,ICA AL008626000              PU81            
MPQ8626GDZ-MPQ8626GD-Z,SMLF,ICA AL008626000              PU82            

----------------

MPQ8633AGLEC807Z-MPQ8633AGLE-CA AL008633007              PU79            

----------------

MPQ8633AGLEC807Z-MPQ8633AGLE-CB AL008633007              PU80            

----------------

MPQ8633BGLEC838Z-MPQ8633BGLE-CA AL008633005              PU73            
MPQ8633BGLEC838Z-MPQ8633BGLE-CA AL008633005              PU181           

----------------

NB695GDZ-NB695GD-Z,SMLF,IC,AL0A AL000695001              PU74            

----------------

NC7SB3157_SMLF-NC7SB3157P6X,NCA ALSB3157000              U21             
NC7SB3157_SMLF-NC7SB3157P6X,NCA ALSB3157000              U22             
NC7SB3157_SMLF-NC7SB3157P6X,NCA ALSB3157000              U60             
NC7SB3157_SMLF-NC7SB3157P6X,NCA ALSB3157000              U61             
NC7SB3157_SMLF-NC7SB3157P6X,NCA ALSB3157000              U85             

----------------

NC7SZ66M5X_SMLF-NC7SZ66M5X,NC7A AL07SZ66004              U16             

----------------

NCP3284MNTXG-NCP3284MNTXG,SMLFA AL003284001              PU9             

----------------

OSC4_SIT1602AI2233E50000000D-5A BF650000037              OSC1            

----------------

PCA9306DCTR-PCA9306DCTR,SMLF,IA AL009306C00              U98             

----------------

PCA9546APWR-PCA9546APWR,SMLF,IA AL09546AK01              U10             
PCA9546APWR-PCA9546APWR,SMLF,IA AL09546AK01              U36             
PCA9546APWR-PCA9546APWR,SMLF,IA AL09546AK01              U141            

----------------

PCA9548APW-PCA9548APW,SMLF,IC,A AL009548K00              U24             

----------------

PCA9555PW_SMLF-PCA9555PW,IC,TMA TMP_QAL009555K04         U51             
PCA9555PW_SMLF-PCA9555PW,IC,TMA TMP_QAL009555K04         U130            
PCA9555PW_SMLF-PCA9555PW,IC,TMA TMP_QAL009555K04         U131            

----------------

PCA9617ADP-PCA9617ADP,SMLF,IC,A AL009617K02              U28             
PCA9617ADP-PCA9617ADP,SMLF,IC,A AL009617K02              U29             
PCA9617ADP-PCA9617ADP,SMLF,IC,A AL009617K02              U30             
PCA9617ADP-PCA9617ADP,SMLF,IC,A AL009617K02              U31             

----------------

PI6CV304LE-PI6CV304LE,SMLF,IC,A AL000304K01              U90             

----------------

Q_CAPP_RDLLF-270UF,16V,20%,OSCA CC72703MD03              C127            

----------------

Q_CAPP_SMLF-100UF,16V,20%,OSCOA CC71003MZ32              PC566           
Q_CAPP_SMLF-100UF,16V,20%,OSCOA CC71003MZ32              PC1215          

----------------

Q_CAPP_SMLF-100UF,16V,20%,POSCA CH7103M8804              C129            
Q_CAPP_SMLF-100UF,16V,20%,POSCA CH7103M8804              C133            
Q_CAPP_SMLF-100UF,16V,20%,POSCA CH7103M8804              C135            
Q_CAPP_SMLF-100UF,16V,20%,POSCA CH7103M8804              C1601           
Q_CAPP_SMLF-100UF,16V,20%,POSCA CH7103M8804              C1603           

----------------

Q_CAPP_SMLF-220UF,6.3V,20%,ALUA CC72201MZ28              PC1845          

----------------

Q_CAPP_SMLF-330UF,2V,35%,SPCAPA CH733RY8807              PC1573          
Q_CAPP_SMLF-330UF,2V,35%,SPCAPA CH733RY8807              PC1575          
Q_CAPP_SMLF-330UF,2V,35%,SPCAPA CH733RY8807              PC1588          
Q_CAPP_SMLF-330UF,2V,35%,SPCAPA CH733RY8807              PC1594          
Q_CAPP_SMLF-330UF,2V,35%,SPCAPA CH733RY8807              PC1910          
Q_CAPP_SMLF-330UF,2V,35%,SPCAPA CH733RY8807              PC1940          

----------------

Q_CAPP_SMLF-470UF,2.5V,20%,EMPA CH747LM8818              PC189           
Q_CAPP_SMLF-470UF,2.5V,20%,EMPA CH747LM8818              PC323           
Q_CAPP_SMLF-470UF,2.5V,20%,EMPA CH747LM8818              PC326           
Q_CAPP_SMLF-470UF,2.5V,20%,EMPA CH747LM8818              PC587           
Q_CAPP_SMLF-470UF,2.5V,20%,EMPA CH747LM8818              PC590           
Q_CAPP_SMLF-470UF,2.5V,20%,EMPA CH747LM8818              PC623           
Q_CAPP_SMLF-470UF,2.5V,20%,EMPA CH747LM8818              PC1187          
Q_CAPP_SMLF-470UF,2.5V,20%,EMPA CH747LM8818              PC1205          
Q_CAPP_SMLF-470UF,2.5V,20%,EMPA CH747LM8818              PC1920          
Q_CAPP_SMLF-470UF,2.5V,20%,EMPA CH747LM8818              PC1990          
Q_CAPP_SMLF-470UF,2.5V,20%,EMPA CH747LM8818              PC2170          
Q_CAPP_SMLF-470UF,2.5V,20%,EMPA CH747LM8818              PC2171          
Q_CAPP_SMLF-470UF,2.5V,20%,EMPA CH747LM8818              PC2336          
Q_CAPP_SMLF-470UF,2.5V,20%,EMPA CH747LM8818              PC2645          

----------------

Q_CAPP_SMLF-470UF,2.5V,20%,SPCA CH747LM8818              PC418           
Q_CAPP_SMLF-470UF,2.5V,20%,SPCA CH747LM8818              PC1900          
Q_CAPP_SMLF-470UF,2.5V,20%,SPCA CH747LM8818              PC1930          
Q_CAPP_SMLF-470UF,2.5V,20%,SPCA CH747LM8818              PC2172          

----------------

Q_CAPP_SMLF-470UF,2V,20%,EMPTYA CH747RM8822              PC1229          

----------------

Q_CAPP_SMLF-470UF,2V,20%,POSCAA CH747RM8822              PC117           

----------------

Q_CAPP_THLF-270UF,16V,20%,OSCOA CC72703MD33              PC207           
Q_CAPP_THLF-270UF,16V,20%,OSCOA CC72703MD33              PC208           
Q_CAPP_THLF-270UF,16V,20%,OSCOA CC72703MD33              PC315           
Q_CAPP_THLF-270UF,16V,20%,OSCOA CC72703MD33              PC318           
Q_CAPP_THLF-270UF,16V,20%,OSCOA CC72703MD33              PC321           
Q_CAPP_THLF-270UF,16V,20%,OSCOA CC72703MD33              PC324           
Q_CAPP_THLF-270UF,16V,20%,OSCOA CC72703MD33              PC417           
Q_CAPP_THLF-270UF,16V,20%,OSCOA CC72703MD33              PC460           
Q_CAPP_THLF-270UF,16V,20%,OSCOA CC72703MD33              PC461           
Q_CAPP_THLF-270UF,16V,20%,OSCOA CC72703MD33              PC579           
Q_CAPP_THLF-270UF,16V,20%,OSCOA CC72703MD33              PC582           
Q_CAPP_THLF-270UF,16V,20%,OSCOA CC72703MD33              PC585           
Q_CAPP_THLF-270UF,16V,20%,OSCOA CC72703MD33              PC588           
Q_CAPP_THLF-270UF,16V,20%,OSCOA CC72703MD33              PC622           
Q_CAPP_THLF-270UF,16V,20%,OSCOA CC72703MD33              PC1189          
Q_CAPP_THLF-270UF,16V,20%,OSCOA CC72703MD33              PC1210          

----------------

Q_CAPP_THLF-560UF,2.5V,20%,EMPA CC7560JMD18              PC621           
Q_CAPP_THLF-560UF,2.5V,20%,EMPA CC7560JMD18              PC1186          

----------------

Q_CAPP_THLF-560UF,2.5V,20%,OSCA CC7560JMD18              PC16            
Q_CAPP_THLF-560UF,2.5V,20%,OSCA CC7560JMD18              PC83            
Q_CAPP_THLF-560UF,2.5V,20%,OSCA CC7560JMD18              PC316           
Q_CAPP_THLF-560UF,2.5V,20%,OSCA CC7560JMD18              PC319           
Q_CAPP_THLF-560UF,2.5V,20%,OSCA CC7560JMD18              PC322           
Q_CAPP_THLF-560UF,2.5V,20%,OSCA CC7560JMD18              PC325           
Q_CAPP_THLF-560UF,2.5V,20%,OSCA CC7560JMD18              PC384           
Q_CAPP_THLF-560UF,2.5V,20%,OSCA CC7560JMD18              PC385           
Q_CAPP_THLF-560UF,2.5V,20%,OSCA CC7560JMD18              PC414           
Q_CAPP_THLF-560UF,2.5V,20%,OSCA CC7560JMD18              PC415           
Q_CAPP_THLF-560UF,2.5V,20%,OSCA CC7560JMD18              PC416           
Q_CAPP_THLF-560UF,2.5V,20%,OSCA CC7560JMD18              PC580           
Q_CAPP_THLF-560UF,2.5V,20%,OSCA CC7560JMD18              PC583           
Q_CAPP_THLF-560UF,2.5V,20%,OSCA CC7560JMD18              PC586           
Q_CAPP_THLF-560UF,2.5V,20%,OSCA CC7560JMD18              PC589           
Q_CAPP_THLF-560UF,2.5V,20%,OSCA CC7560JMD18              PC619           
Q_CAPP_THLF-560UF,2.5V,20%,OSCA CC7560JMD18              PC620           
Q_CAPP_THLF-560UF,2.5V,20%,OSCA CC7560JMD18              PC1183          
Q_CAPP_THLF-560UF,2.5V,20%,OSCA CC7560JMD18              PC1185          
Q_CAPP_THLF-560UF,2.5V,20%,OSCA CC7560JMD18              PC1201          
Q_CAPP_THLF-560UF,2.5V,20%,OSCA CC7560JMD18              PC1203          
Q_CAPP_THLF-560UF,2.5V,20%,OSCA CC7560JMD18              PC1204          
Q_CAPP_THLF-560UF,2.5V,20%,OSCA CC7560JMD18              PC1227          
Q_CAPP_THLF-560UF,2.5V,20%,OSCA CC7560JMD18              PC1230          
Q_CAPP_THLF-560UF,2.5V,20%,OSCA CC7560JMD18              PC1574          
Q_CAPP_THLF-560UF,2.5V,20%,OSCA CC7560JMD18              PC1576          
Q_CAPP_THLF-560UF,2.5V,20%,OSCA CC7560JMD18              PC1579          
Q_CAPP_THLF-560UF,2.5V,20%,OSCA CC7560JMD18              PC1593          
Q_CAPP_THLF-560UF,2.5V,20%,OSCA CC7560JMD18              PC1595          
Q_CAPP_THLF-560UF,2.5V,20%,OSCA CC7560JMD18              PC1596          
Q_CAPP_THLF-560UF,2.5V,20%,OSCA CC7560JMD18              PC1644          
Q_CAPP_THLF-560UF,2.5V,20%,OSCA CC7560JMD18              PC1645          
Q_CAPP_THLF-560UF,2.5V,20%,OSCA CC7560JMD18              PC2180          
Q_CAPP_THLF-560UF,2.5V,20%,OSCA CC7560JMD18              PC2199          

----------------

Q_CAPP_THLF-560UF,6.3V,20%,EMPA CC75601MD18              PC1258          

----------------

Q_CAPP_THLF-560UF,6.3V,20%,OSCA CC75601MD18              PC1771          
Q_CAPP_THLF-560UF,6.3V,20%,OSCA CC75601MD18              PC1866          
Q_CAPP_THLF-560UF,6.3V,20%,OSCA CC75601MD18              PC1867          

----------------

Q_CAP_0402-0.01UF,25V,10%,X7R,A CH31004KB17              PC2287          

----------------

Q_CAP_0402-0.022UF,16V,10%,EMPA CH32203KB11              PC2001          

----------------

Q_CAP_0402-0.022UF,16V,10%,X7RA CH32203KB11              PC2000          
Q_CAP_0402-0.022UF,16V,10%,X7RA CH32203KB11              PC2002          

----------------

Q_CAP_0402-0.1UF,25V,10%,EMPTYA CH4104K1B00              C1124           
Q_CAP_0402-0.1UF,25V,10%,EMPTYA CH4104K1B00              C1130           
Q_CAP_0402-0.1UF,25V,10%,EMPTYA CH4104K1B00              C1136           
Q_CAP_0402-0.1UF,25V,10%,EMPTYA CH4104K1B00              C1140           
Q_CAP_0402-0.1UF,25V,10%,EMPTYA CH4104K1B00              C1144           
Q_CAP_0402-0.1UF,25V,10%,EMPTYA CH4104K1B00              C1148           
Q_CAP_0402-0.1UF,25V,10%,EMPTYA CH4104K1B00              C1324           
Q_CAP_0402-0.1UF,25V,10%,EMPTYA CH4104K1B00              PC214           
Q_CAP_0402-0.1UF,25V,10%,EMPTYA CH4104K1B00              PC329           
Q_CAP_0402-0.1UF,25V,10%,EMPTYA CH4104K1B00              PC467           
Q_CAP_0402-0.1UF,25V,10%,EMPTYA CH4104K1B00              PC547           
Q_CAP_0402-0.1UF,25V,10%,EMPTYA CH4104K1B00              PC1249          
Q_CAP_0402-0.1UF,25V,10%,EMPTYA CH4104K1B00              PC1251          
Q_CAP_0402-0.1UF,25V,10%,EMPTYA CH4104K1B00              PC1254          
Q_CAP_0402-0.1UF,25V,10%,EMPTYA CH4104K1B00              PC1351          
Q_CAP_0402-0.1UF,25V,10%,EMPTYA CH4104K1B00              PC1352          
Q_CAP_0402-0.1UF,25V,10%,EMPTYA CH4104K1B00              PC1870          

----------------

Q_CAP_0402-0.1UF,25V,10%,X7R,CA CH4104K1B00              C110            
Q_CAP_0402-0.1UF,25V,10%,X7R,CA CH4104K1B00              C111            
Q_CAP_0402-0.1UF,25V,10%,X7R,CA CH4104K1B00              C112            
Q_CAP_0402-0.1UF,25V,10%,X7R,CA CH4104K1B00              C114            
Q_CAP_0402-0.1UF,25V,10%,X7R,CA CH4104K1B00              C115            
Q_CAP_0402-0.1UF,25V,10%,X7R,CA CH4104K1B00              C116            
Q_CAP_0402-0.1UF,25V,10%,X7R,CA CH4104K1B00              C117            
Q_CAP_0402-0.1UF,25V,10%,X7R,CA CH4104K1B00              C119            
Q_CAP_0402-0.1UF,25V,10%,X7R,CA CH4104K1B00              C120            
Q_CAP_0402-0.1UF,25V,10%,X7R,CA CH4104K1B00              C128            
Q_CAP_0402-0.1UF,25V,10%,X7R,CA CH4104K1B00              C130            
Q_CAP_0402-0.1UF,25V,10%,X7R,CA CH4104K1B00              C132            
Q_CAP_0402-0.1UF,25V,10%,X7R,CA CH4104K1B00              C134            
Q_CAP_0402-0.1UF,25V,10%,X7R,CA CH4104K1B00              C136            
Q_CAP_0402-0.1UF,25V,10%,X7R,CA CH4104K1B00              C138            
Q_CAP_0402-0.1UF,25V,10%,X7R,CA CH4104K1B00              C171            
Q_CAP_0402-0.1UF,25V,10%,X7R,CA CH4104K1B00              C173            
Q_CAP_0402-0.1UF,25V,10%,X7R,CA CH4104K1B00              C174            
Q_CAP_0402-0.1UF,25V,10%,X7R,CA CH4104K1B00              C180            
Q_CAP_0402-0.1UF,25V,10%,X7R,CA CH4104K1B00              C188            
Q_CAP_0402-0.1UF,25V,10%,X7R,CA CH4104K1B00              C204            
Q_CAP_0402-0.1UF,25V,10%,X7R,CA CH4104K1B00              C205            
Q_CAP_0402-0.1UF,25V,10%,X7R,CA CH4104K1B00              C206            
Q_CAP_0402-0.1UF,25V,10%,X7R,CA CH4104K1B00              C207            
Q_CAP_0402-0.1UF,25V,10%,X7R,CA CH4104K1B00              C210            
Q_CAP_0402-0.1UF,25V,10%,X7R,CA CH4104K1B00              C211            
Q_CAP_0402-0.1UF,25V,10%,X7R,CA CH4104K1B00              C536            
Q_CAP_0402-0.1UF,25V,10%,X7R,CA CH4104K1B00              C537            
Q_CAP_0402-0.1UF,25V,10%,X7R,CA CH4104K1B00              C538            
Q_CAP_0402-0.1UF,25V,10%,X7R,CA CH4104K1B00              C539            
Q_CAP_0402-0.1UF,25V,10%,X7R,CA CH4104K1B00              C540            
Q_CAP_0402-0.1UF,25V,10%,X7R,CA CH4104K1B00              C543            
Q_CAP_0402-0.1UF,25V,10%,X7R,CA CH4104K1B00              C544            
Q_CAP_0402-0.1UF,25V,10%,X7R,CA CH4104K1B00              C548            
Q_CAP_0402-0.1UF,25V,10%,X7R,CA CH4104K1B00              C549            
Q_CAP_0402-0.1UF,25V,10%,X7R,CA CH4104K1B00              C552            
Q_CAP_0402-0.1UF,25V,10%,X7R,CA CH4104K1B00              C553            
Q_CAP_0402-0.1UF,25V,10%,X7R,CA CH4104K1B00              C554            
Q_CAP_0402-0.1UF,25V,10%,X7R,CA CH4104K1B00              C559            
Q_CAP_0402-0.1UF,25V,10%,X7R,CA CH4104K1B00              C560            
Q_CAP_0402-0.1UF,25V,10%,X7R,CA CH4104K1B00              C561            
Q_CAP_0402-0.1UF,25V,10%,X7R,CA CH4104K1B00              C562            
Q_CAP_0402-0.1UF,25V,10%,X7R,CA CH4104K1B00              C564            
Q_CAP_0402-0.1UF,25V,10%,X7R,CA CH4104K1B00              C565            
Q_CAP_0402-0.1UF,25V,10%,X7R,CA CH4104K1B00              C566            
Q_CAP_0402-0.1UF,25V,10%,X7R,CA CH4104K1B00              C567            
Q_CAP_0402-0.1UF,25V,10%,X7R,CA CH4104K1B00              C568            
Q_CAP_0402-0.1UF,25V,10%,X7R,CA CH4104K1B00              C569            
Q_CAP_0402-0.1UF,25V,10%,X7R,CA CH4104K1B00              C570            
Q_CAP_0402-0.1UF,25V,10%,X7R,CA CH4104K1B00              C578            
Q_CAP_0402-0.1UF,25V,10%,X7R,CA CH4104K1B00              C579            
Q_CAP_0402-0.1UF,25V,10%,X7R,CA CH4104K1B00              C580            
Q_CAP_0402-0.1UF,25V,10%,X7R,CA CH4104K1B00              C581            
Q_CAP_0402-0.1UF,25V,10%,X7R,CA CH4104K1B00              C586            
Q_CAP_0402-0.1UF,25V,10%,X7R,CA CH4104K1B00              C592            
Q_CAP_0402-0.1UF,25V,10%,X7R,CA CH4104K1B00              C593            
Q_CAP_0402-0.1UF,25V,10%,X7R,CA CH4104K1B00              C607            
Q_CAP_0402-0.1UF,25V,10%,X7R,CA CH4104K1B00              C608            
Q_CAP_0402-0.1UF,25V,10%,X7R,CA CH4104K1B00              C609            
Q_CAP_0402-0.1UF,25V,10%,X7R,CA CH4104K1B00              C629            
Q_CAP_0402-0.1UF,25V,10%,X7R,CA CH4104K1B00              C630            
Q_CAP_0402-0.1UF,25V,10%,X7R,CA CH4104K1B00              C631            
Q_CAP_0402-0.1UF,25V,10%,X7R,CA CH4104K1B00              C638            
Q_CAP_0402-0.1UF,25V,10%,X7R,CA CH4104K1B00              C639            
Q_CAP_0402-0.1UF,25V,10%,X7R,CA CH4104K1B00              C640            
Q_CAP_0402-0.1UF,25V,10%,X7R,CA CH4104K1B00              C641            
Q_CAP_0402-0.1UF,25V,10%,X7R,CA CH4104K1B00              C1048           
Q_CAP_0402-0.1UF,25V,10%,X7R,CA CH4104K1B00              C1049           
Q_CAP_0402-0.1UF,25V,10%,X7R,CA CH4104K1B00              C1050           
Q_CAP_0402-0.1UF,25V,10%,X7R,CA CH4104K1B00              C1051           
Q_CAP_0402-0.1UF,25V,10%,X7R,CA CH4104K1B00              C1052           
Q_CAP_0402-0.1UF,25V,10%,X7R,CA CH4104K1B00              C1056           
Q_CAP_0402-0.1UF,25V,10%,X7R,CA CH4104K1B00              C1057           
Q_CAP_0402-0.1UF,25V,10%,X7R,CA CH4104K1B00              C1058           
Q_CAP_0402-0.1UF,25V,10%,X7R,CA CH4104K1B00              C1059           
Q_CAP_0402-0.1UF,25V,10%,X7R,CA CH4104K1B00              C1060           
Q_CAP_0402-0.1UF,25V,10%,X7R,CA CH4104K1B00              C1064           
Q_CAP_0402-0.1UF,25V,10%,X7R,CA CH4104K1B00              C1065           
Q_CAP_0402-0.1UF,25V,10%,X7R,CA CH4104K1B00              C1066           
Q_CAP_0402-0.1UF,25V,10%,X7R,CA CH4104K1B00              C1067           
Q_CAP_0402-0.1UF,25V,10%,X7R,CA CH4104K1B00              C1068           
Q_CAP_0402-0.1UF,25V,10%,X7R,CA CH4104K1B00              C1084           
Q_CAP_0402-0.1UF,25V,10%,X7R,CA CH4104K1B00              C1086           
Q_CAP_0402-0.1UF,25V,10%,X7R,CA CH4104K1B00              C1088           
Q_CAP_0402-0.1UF,25V,10%,X7R,CA CH4104K1B00              C1107           
Q_CAP_0402-0.1UF,25V,10%,X7R,CA CH4104K1B00              C1108           
Q_CAP_0402-0.1UF,25V,10%,X7R,CA CH4104K1B00              C1110           
Q_CAP_0402-0.1UF,25V,10%,X7R,CA CH4104K1B00              C1111           
Q_CAP_0402-0.1UF,25V,10%,X7R,CA CH4104K1B00              C1113           
Q_CAP_0402-0.1UF,25V,10%,X7R,CA CH4104K1B00              C1114           
Q_CAP_0402-0.1UF,25V,10%,X7R,CA CH4104K1B00              C1118           
Q_CAP_0402-0.1UF,25V,10%,X7R,CA CH4104K1B00              C1119           
Q_CAP_0402-0.1UF,25V,10%,X7R,CA CH4104K1B00              C1120           
Q_CAP_0402-0.1UF,25V,10%,X7R,CA CH4104K1B00              C1122           
Q_CAP_0402-0.1UF,25V,10%,X7R,CA CH4104K1B00              C1123           
Q_CAP_0402-0.1UF,25V,10%,X7R,CA CH4104K1B00              C1127           
Q_CAP_0402-0.1UF,25V,10%,X7R,CA CH4104K1B00              C1128           
Q_CAP_0402-0.1UF,25V,10%,X7R,CA CH4104K1B00              C1129           
Q_CAP_0402-0.1UF,25V,10%,X7R,CA CH4104K1B00              C1133           
Q_CAP_0402-0.1UF,25V,10%,X7R,CA CH4104K1B00              C1134           
Q_CAP_0402-0.1UF,25V,10%,X7R,CA CH4104K1B00              C1135           
Q_CAP_0402-0.1UF,25V,10%,X7R,CA CH4104K1B00              C1138           
Q_CAP_0402-0.1UF,25V,10%,X7R,CA CH4104K1B00              C1139           
Q_CAP_0402-0.1UF,25V,10%,X7R,CA CH4104K1B00              C1142           
Q_CAP_0402-0.1UF,25V,10%,X7R,CA CH4104K1B00              C1143           
Q_CAP_0402-0.1UF,25V,10%,X7R,CA CH4104K1B00              C1146           
Q_CAP_0402-0.1UF,25V,10%,X7R,CA CH4104K1B00              C1147           
Q_CAP_0402-0.1UF,25V,10%,X7R,CA CH4104K1B00              C1150           
Q_CAP_0402-0.1UF,25V,10%,X7R,CA CH4104K1B00              C1151           
Q_CAP_0402-0.1UF,25V,10%,X7R,CA CH4104K1B00              C1152           
Q_CAP_0402-0.1UF,25V,10%,X7R,CA CH4104K1B00              C1153           
Q_CAP_0402-0.1UF,25V,10%,X7R,CA CH4104K1B00              C1154           
Q_CAP_0402-0.1UF,25V,10%,X7R,CA CH4104K1B00              C1155           
Q_CAP_0402-0.1UF,25V,10%,X7R,CA CH4104K1B00              C1156           
Q_CAP_0402-0.1UF,25V,10%,X7R,CA CH4104K1B00              C1157           
Q_CAP_0402-0.1UF,25V,10%,X7R,CA CH4104K1B00              C1158           
Q_CAP_0402-0.1UF,25V,10%,X7R,CA CH4104K1B00              C1159           
Q_CAP_0402-0.1UF,25V,10%,X7R,CA CH4104K1B00              C1160           
Q_CAP_0402-0.1UF,25V,10%,X7R,CA CH4104K1B00              C1161           
Q_CAP_0402-0.1UF,25V,10%,X7R,CA CH4104K1B00              C1162           
Q_CAP_0402-0.1UF,25V,10%,X7R,CA CH4104K1B00              C1163           
Q_CAP_0402-0.1UF,25V,10%,X7R,CA CH4104K1B00              C1164           
Q_CAP_0402-0.1UF,25V,10%,X7R,CA CH4104K1B00              C1165           
Q_CAP_0402-0.1UF,25V,10%,X7R,CA CH4104K1B00              C1166           
Q_CAP_0402-0.1UF,25V,10%,X7R,CA CH4104K1B00              C1167           
Q_CAP_0402-0.1UF,25V,10%,X7R,CA CH4104K1B00              C1168           
Q_CAP_0402-0.1UF,25V,10%,X7R,CA CH4104K1B00              C1169           
Q_CAP_0402-0.1UF,25V,10%,X7R,CA CH4104K1B00              C1173           
Q_CAP_0402-0.1UF,25V,10%,X7R,CA CH4104K1B00              C1175           
Q_CAP_0402-0.1UF,25V,10%,X7R,CA CH4104K1B00              C1208           
Q_CAP_0402-0.1UF,25V,10%,X7R,CA CH4104K1B00              C1215           
Q_CAP_0402-0.1UF,25V,10%,X7R,CA CH4104K1B00              C1216           
Q_CAP_0402-0.1UF,25V,10%,X7R,CA CH4104K1B00              C1217           
Q_CAP_0402-0.1UF,25V,10%,X7R,CA CH4104K1B00              C1218           
Q_CAP_0402-0.1UF,25V,10%,X7R,CA CH4104K1B00              C1219           
Q_CAP_0402-0.1UF,25V,10%,X7R,CA CH4104K1B00              C1229           
Q_CAP_0402-0.1UF,25V,10%,X7R,CA CH4104K1B00              C1233           
Q_CAP_0402-0.1UF,25V,10%,X7R,CA CH4104K1B00              C1234           
Q_CAP_0402-0.1UF,25V,10%,X7R,CA CH4104K1B00              C1235           
Q_CAP_0402-0.1UF,25V,10%,X7R,CA CH4104K1B00              C1236           
Q_CAP_0402-0.1UF,25V,10%,X7R,CA CH4104K1B00              C1237           
Q_CAP_0402-0.1UF,25V,10%,X7R,CA CH4104K1B00              C1238           
Q_CAP_0402-0.1UF,25V,10%,X7R,CA CH4104K1B00              C1239           
Q_CAP_0402-0.1UF,25V,10%,X7R,CA CH4104K1B00              C1240           
Q_CAP_0402-0.1UF,25V,10%,X7R,CA CH4104K1B00              C1241           
Q_CAP_0402-0.1UF,25V,10%,X7R,CA CH4104K1B00              C1274           
Q_CAP_0402-0.1UF,25V,10%,X7R,CA CH4104K1B00              C1275           
Q_CAP_0402-0.1UF,25V,10%,X7R,CA CH4104K1B00              C1278           
Q_CAP_0402-0.1UF,25V,10%,X7R,CA CH4104K1B00              C1279           
Q_CAP_0402-0.1UF,25V,10%,X7R,CA CH4104K1B00              C1280           
Q_CAP_0402-0.1UF,25V,10%,X7R,CA CH4104K1B00              C1281           
Q_CAP_0402-0.1UF,25V,10%,X7R,CA CH4104K1B00              C1282           
Q_CAP_0402-0.1UF,25V,10%,X7R,CA CH4104K1B00              C1283           
Q_CAP_0402-0.1UF,25V,10%,X7R,CA CH4104K1B00              C1284           
Q_CAP_0402-0.1UF,25V,10%,X7R,CA CH4104K1B00              C1285           
Q_CAP_0402-0.1UF,25V,10%,X7R,CA CH4104K1B00              C1288           
Q_CAP_0402-0.1UF,25V,10%,X7R,CA CH4104K1B00              C1292           
Q_CAP_0402-0.1UF,25V,10%,X7R,CA CH4104K1B00              C1305           
Q_CAP_0402-0.1UF,25V,10%,X7R,CA CH4104K1B00              C1317           
Q_CAP_0402-0.1UF,25V,10%,X7R,CA CH4104K1B00              C1320           
Q_CAP_0402-0.1UF,25V,10%,X7R,CA CH4104K1B00              C1321           
Q_CAP_0402-0.1UF,25V,10%,X7R,CA CH4104K1B00              C1322           
Q_CAP_0402-0.1UF,25V,10%,X7R,CA CH4104K1B00              C1323           
Q_CAP_0402-0.1UF,25V,10%,X7R,CA CH4104K1B00              C1325           
Q_CAP_0402-0.1UF,25V,10%,X7R,CA CH4104K1B00              C1344           
Q_CAP_0402-0.1UF,25V,10%,X7R,CA CH4104K1B00              C1345           
Q_CAP_0402-0.1UF,25V,10%,X7R,CA CH4104K1B00              C1346           
Q_CAP_0402-0.1UF,25V,10%,X7R,CA CH4104K1B00              C1347           
Q_CAP_0402-0.1UF,25V,10%,X7R,CA CH4104K1B00              C1351           
Q_CAP_0402-0.1UF,25V,10%,X7R,CA CH4104K1B00              C1358           
Q_CAP_0402-0.1UF,25V,10%,X7R,CA CH4104K1B00              C1360           
Q_CAP_0402-0.1UF,25V,10%,X7R,CA CH4104K1B00              C1408           
Q_CAP_0402-0.1UF,25V,10%,X7R,CA CH4104K1B00              C1430           
Q_CAP_0402-0.1UF,25V,10%,X7R,CA CH4104K1B00              C1432           
Q_CAP_0402-0.1UF,25V,10%,X7R,CA CH4104K1B00              C1440           
Q_CAP_0402-0.1UF,25V,10%,X7R,CA CH4104K1B00              C1441           
Q_CAP_0402-0.1UF,25V,10%,X7R,CA CH4104K1B00              C1442           
Q_CAP_0402-0.1UF,25V,10%,X7R,CA CH4104K1B00              C1443           
Q_CAP_0402-0.1UF,25V,10%,X7R,CA CH4104K1B00              C1444           
Q_CAP_0402-0.1UF,25V,10%,X7R,CA CH4104K1B00              C1446           
Q_CAP_0402-0.1UF,25V,10%,X7R,CA CH4104K1B00              C1447           
Q_CAP_0402-0.1UF,25V,10%,X7R,CA CH4104K1B00              C1450           
Q_CAP_0402-0.1UF,25V,10%,X7R,CA CH4104K1B00              C1451           
Q_CAP_0402-0.1UF,25V,10%,X7R,CA CH4104K1B00              C1452           
Q_CAP_0402-0.1UF,25V,10%,X7R,CA CH4104K1B00              C1453           
Q_CAP_0402-0.1UF,25V,10%,X7R,CA CH4104K1B00              C1454           
Q_CAP_0402-0.1UF,25V,10%,X7R,CA CH4104K1B00              C1456           
Q_CAP_0402-0.1UF,25V,10%,X7R,CA CH4104K1B00              C1457           
Q_CAP_0402-0.1UF,25V,10%,X7R,CA CH4104K1B00              C1460           
Q_CAP_0402-0.1UF,25V,10%,X7R,CA CH4104K1B00              C1461           
Q_CAP_0402-0.1UF,25V,10%,X7R,CA CH4104K1B00              C1462           
Q_CAP_0402-0.1UF,25V,10%,X7R,CA CH4104K1B00              C1463           
Q_CAP_0402-0.1UF,25V,10%,X7R,CA CH4104K1B00              C1464           
Q_CAP_0402-0.1UF,25V,10%,X7R,CA CH4104K1B00              C1466           
Q_CAP_0402-0.1UF,25V,10%,X7R,CA CH4104K1B00              C1467           
Q_CAP_0402-0.1UF,25V,10%,X7R,CA CH4104K1B00              C1470           
Q_CAP_0402-0.1UF,25V,10%,X7R,CA CH4104K1B00              C1471           
Q_CAP_0402-0.1UF,25V,10%,X7R,CA CH4104K1B00              C1472           
Q_CAP_0402-0.1UF,25V,10%,X7R,CA CH4104K1B00              C1473           
Q_CAP_0402-0.1UF,25V,10%,X7R,CA CH4104K1B00              C1474           
Q_CAP_0402-0.1UF,25V,10%,X7R,CA CH4104K1B00              C1476           
Q_CAP_0402-0.1UF,25V,10%,X7R,CA CH4104K1B00              C1477           
Q_CAP_0402-0.1UF,25V,10%,X7R,CA CH4104K1B00              C1481           
Q_CAP_0402-0.1UF,25V,10%,X7R,CA CH4104K1B00              C1482           
Q_CAP_0402-0.1UF,25V,10%,X7R,CA CH4104K1B00              C1485           
Q_CAP_0402-0.1UF,25V,10%,X7R,CA CH4104K1B00              C1486           
Q_CAP_0402-0.1UF,25V,10%,X7R,CA CH4104K1B00              C1495           
Q_CAP_0402-0.1UF,25V,10%,X7R,CA CH4104K1B00              C1496           
Q_CAP_0402-0.1UF,25V,10%,X7R,CA CH4104K1B00              C1497           
Q_CAP_0402-0.1UF,25V,10%,X7R,CA CH4104K1B00              C1498           
Q_CAP_0402-0.1UF,25V,10%,X7R,CA CH4104K1B00              C1499           
Q_CAP_0402-0.1UF,25V,10%,X7R,CA CH4104K1B00              C1500           
Q_CAP_0402-0.1UF,25V,10%,X7R,CA CH4104K1B00              C1501           
Q_CAP_0402-0.1UF,25V,10%,X7R,CA CH4104K1B00              C1502           
Q_CAP_0402-0.1UF,25V,10%,X7R,CA CH4104K1B00              C1505           
Q_CAP_0402-0.1UF,25V,10%,X7R,CA CH4104K1B00              C1512           
Q_CAP_0402-0.1UF,25V,10%,X7R,CA CH4104K1B00              C1513           
Q_CAP_0402-0.1UF,25V,10%,X7R,CA CH4104K1B00              C1588           
Q_CAP_0402-0.1UF,25V,10%,X7R,CA CH4104K1B00              C1589           
Q_CAP_0402-0.1UF,25V,10%,X7R,CA CH4104K1B00              C1590           
Q_CAP_0402-0.1UF,25V,10%,X7R,CA CH4104K1B00              C1591           
Q_CAP_0402-0.1UF,25V,10%,X7R,CA CH4104K1B00              C1592           
Q_CAP_0402-0.1UF,25V,10%,X7R,CA CH4104K1B00              C1593           
Q_CAP_0402-0.1UF,25V,10%,X7R,CA CH4104K1B00              C1594           
Q_CAP_0402-0.1UF,25V,10%,X7R,CA CH4104K1B00              C1595           
Q_CAP_0402-0.1UF,25V,10%,X7R,CA CH4104K1B00              C1597           
Q_CAP_0402-0.1UF,25V,10%,X7R,CA CH4104K1B00              C1602           
Q_CAP_0402-0.1UF,25V,10%,X7R,CA CH4104K1B00              C1604           
Q_CAP_0402-0.1UF,25V,10%,X7R,CA CH4104K1B00              C1606           
Q_CAP_0402-0.1UF,25V,10%,X7R,CA CH4104K1B00              C1607           
Q_CAP_0402-0.1UF,25V,10%,X7R,CA CH4104K1B00              C2444           
Q_CAP_0402-0.1UF,25V,10%,X7R,CA CH4104K1B00              PC221           
Q_CAP_0402-0.1UF,25V,10%,X7R,CA CH4104K1B00              PC330           
Q_CAP_0402-0.1UF,25V,10%,X7R,CA CH4104K1B00              PC386           
Q_CAP_0402-0.1UF,25V,10%,X7R,CA CH4104K1B00              PC390           
Q_CAP_0402-0.1UF,25V,10%,X7R,CA CH4104K1B00              PC474           
Q_CAP_0402-0.1UF,25V,10%,X7R,CA CH4104K1B00              PC548           
Q_CAP_0402-0.1UF,25V,10%,X7R,CA CH4104K1B00              PC577           
Q_CAP_0402-0.1UF,25V,10%,X7R,CA CH4104K1B00              PC624           
Q_CAP_0402-0.1UF,25V,10%,X7R,CA CH4104K1B00              PC628           
Q_CAP_0402-0.1UF,25V,10%,X7R,CA CH4104K1B00              PC1219          
Q_CAP_0402-0.1UF,25V,10%,X7R,CA CH4104K1B00              PC1221          
Q_CAP_0402-0.1UF,25V,10%,X7R,CA CH4104K1B00              PC1224          
Q_CAP_0402-0.1UF,25V,10%,X7R,CA CH4104K1B00              PC1262          
Q_CAP_0402-0.1UF,25V,10%,X7R,CA CH4104K1B00              PC1264          
Q_CAP_0402-0.1UF,25V,10%,X7R,CA CH4104K1B00              PC1267          
Q_CAP_0402-0.1UF,25V,10%,X7R,CA CH4104K1B00              PC1337          
Q_CAP_0402-0.1UF,25V,10%,X7R,CA CH4104K1B00              PC1338          
Q_CAP_0402-0.1UF,25V,10%,X7R,CA CH4104K1B00              PC1339          
Q_CAP_0402-0.1UF,25V,10%,X7R,CA CH4104K1B00              PC1340          
Q_CAP_0402-0.1UF,25V,10%,X7R,CA CH4104K1B00              PC1341          
Q_CAP_0402-0.1UF,25V,10%,X7R,CA CH4104K1B00              PC1342          
Q_CAP_0402-0.1UF,25V,10%,X7R,CA CH4104K1B00              PC1343          
Q_CAP_0402-0.1UF,25V,10%,X7R,CA CH4104K1B00              PC1344          
Q_CAP_0402-0.1UF,25V,10%,X7R,CA CH4104K1B00              PC1345          
Q_CAP_0402-0.1UF,25V,10%,X7R,CA CH4104K1B00              PC1346          
Q_CAP_0402-0.1UF,25V,10%,X7R,CA CH4104K1B00              PC1347          
Q_CAP_0402-0.1UF,25V,10%,X7R,CA CH4104K1B00              PC1348          
Q_CAP_0402-0.1UF,25V,10%,X7R,CA CH4104K1B00              PC1349          
Q_CAP_0402-0.1UF,25V,10%,X7R,CA CH4104K1B00              PC1350          
Q_CAP_0402-0.1UF,25V,10%,X7R,CA CH4104K1B00              PC1354          
Q_CAP_0402-0.1UF,25V,10%,X7R,CA CH4104K1B00              PC1355          
Q_CAP_0402-0.1UF,25V,10%,X7R,CA CH4104K1B00              PC1356          
Q_CAP_0402-0.1UF,25V,10%,X7R,CA CH4104K1B00              PC1358          
Q_CAP_0402-0.1UF,25V,10%,X7R,CA CH4104K1B00              PC1359          
Q_CAP_0402-0.1UF,25V,10%,X7R,CA CH4104K1B00              PC1360          
Q_CAP_0402-0.1UF,25V,10%,X7R,CA CH4104K1B00              PC1361          
Q_CAP_0402-0.1UF,25V,10%,X7R,CA CH4104K1B00              PC1362          
Q_CAP_0402-0.1UF,25V,10%,X7R,CA CH4104K1B00              PC1363          
Q_CAP_0402-0.1UF,25V,10%,X7R,CA CH4104K1B00              PC1364          
Q_CAP_0402-0.1UF,25V,10%,X7R,CA CH4104K1B00              PC1365          
Q_CAP_0402-0.1UF,25V,10%,X7R,CA CH4104K1B00              PC1366          
Q_CAP_0402-0.1UF,25V,10%,X7R,CA CH4104K1B00              PC1367          
Q_CAP_0402-0.1UF,25V,10%,X7R,CA CH4104K1B00              PC1368          
Q_CAP_0402-0.1UF,25V,10%,X7R,CA CH4104K1B00              PC1369          
Q_CAP_0402-0.1UF,25V,10%,X7R,CA CH4104K1B00              PC1370          
Q_CAP_0402-0.1UF,25V,10%,X7R,CA CH4104K1B00              PC1371          
Q_CAP_0402-0.1UF,25V,10%,X7R,CA CH4104K1B00              PC1846          
Q_CAP_0402-0.1UF,25V,10%,X7R,CA CH4104K1B00              PC1852          
Q_CAP_0402-0.1UF,25V,10%,X7R,CA CH4104K1B00              PC1853          
Q_CAP_0402-0.1UF,25V,10%,X7R,CA CH4104K1B00              PC1869          

----------------

Q_CAP_0402-0.22UF,16V,10%,EMPTA CH4223K1B00              PC1252          

----------------

Q_CAP_0402-0.22UF,16V,10%,X7R,A CH4223K1B00              C1226           
Q_CAP_0402-0.22UF,16V,10%,X7R,A CH4223K1B00              PC568           
Q_CAP_0402-0.22UF,16V,10%,X7R,A CH4223K1B00              PC1222          
Q_CAP_0402-0.22UF,16V,10%,X7R,A CH4223K1B00              PC1235          
Q_CAP_0402-0.22UF,16V,10%,X7R,A CH4223K1B00              PC1265          
Q_CAP_0402-0.22UF,16V,10%,X7R,A CH4223K1B00              PC1275          
Q_CAP_0402-0.22UF,16V,10%,X7R,A CH4223K1B00              PC1283          
Q_CAP_0402-0.22UF,16V,10%,X7R,A CH4223K1B00              PC1847          

----------------

Q_CAP_0402-1000PF,50V,5%,EMPTYA CH21006JB10              C1286           
Q_CAP_0402-1000PF,50V,5%,EMPTYA CH21006JB10              C1300           
Q_CAP_0402-1000PF,50V,5%,EMPTYA CH21006JB10              C1301           
Q_CAP_0402-1000PF,50V,5%,EMPTYA CH21006JB10              C1307           
Q_CAP_0402-1000PF,50V,5%,EMPTYA CH21006JB10              C1308           
Q_CAP_0402-1000PF,50V,5%,EMPTYA CH21006JB10              C2445           
Q_CAP_0402-1000PF,50V,5%,EMPTYA CH21006JB10              PC218           
Q_CAP_0402-1000PF,50V,5%,EMPTYA CH21006JB10              PC220           
Q_CAP_0402-1000PF,50V,5%,EMPTYA CH21006JB10              PC333           
Q_CAP_0402-1000PF,50V,5%,EMPTYA CH21006JB10              PC388           
Q_CAP_0402-1000PF,50V,5%,EMPTYA CH21006JB10              PC421           
Q_CAP_0402-1000PF,50V,5%,EMPTYA CH21006JB10              PC471           
Q_CAP_0402-1000PF,50V,5%,EMPTYA CH21006JB10              PC473           
Q_CAP_0402-1000PF,50V,5%,EMPTYA CH21006JB10              PC551           
Q_CAP_0402-1000PF,50V,5%,EMPTYA CH21006JB10              PC593           
Q_CAP_0402-1000PF,50V,5%,EMPTYA CH21006JB10              PC626           

----------------

Q_CAP_0402-1000PF,50V,5%,X7R,TA CH21006JB10              C1296           
Q_CAP_0402-1000PF,50V,5%,X7R,TA CH21006JB10              C1297           
Q_CAP_0402-1000PF,50V,5%,X7R,TA CH21006JB10              C2446           
Q_CAP_0402-1000PF,50V,5%,X7R,TA CH21006JB10              PC217           
Q_CAP_0402-1000PF,50V,5%,X7R,TA CH21006JB10              PC219           
Q_CAP_0402-1000PF,50V,5%,X7R,TA CH21006JB10              PC332           
Q_CAP_0402-1000PF,50V,5%,X7R,TA CH21006JB10              PC420           
Q_CAP_0402-1000PF,50V,5%,X7R,TA CH21006JB10              PC470           
Q_CAP_0402-1000PF,50V,5%,X7R,TA CH21006JB10              PC472           
Q_CAP_0402-1000PF,50V,5%,X7R,TA CH21006JB10              PC550           
Q_CAP_0402-1000PF,50V,5%,X7R,TA CH21006JB10              PC592           

----------------

Q_CAP_0402-100PF,50V,5%,EMPTY,A CH11006JB00              PC1253          

----------------

Q_CAP_0402-100PF,50V,5%,NPO,CHA CH11006JB00              PC1266          

----------------

Q_CAP_0402-100PF,50V,5%,X7R,CHA CH11006JB18              C1209           
Q_CAP_0402-100PF,50V,5%,X7R,CHA CH11006JB18              C1211           

----------------

Q_CAP_0402-10PF,50V,1%,NPO,TMPA CH0106F0B00              PC569           

----------------

Q_CAP_0402-15PF,50V,5%,C0G,CH0A CH01506JB06              C113            
Q_CAP_0402-15PF,50V,5%,C0G,CH0A CH01506JB06              C118            

----------------

Q_CAP_0402-1NF,50V,10%,X7R,CH2A CH21006KB16              C1580           
Q_CAP_0402-1NF,50V,10%,X7R,CH2A CH21006KB16              C1585           

----------------

Q_CAP_0402-1UF,6.3V,10%,EMPTY,A CH5101K1B01              C1250           
Q_CAP_0402-1UF,6.3V,10%,EMPTY,A CH5101K1B01              C1253           
Q_CAP_0402-1UF,6.3V,10%,EMPTY,A CH5101K1B01              C1256           
Q_CAP_0402-1UF,6.3V,10%,EMPTY,A CH5101K1B01              C1257           
Q_CAP_0402-1UF,6.3V,10%,EMPTY,A CH5101K1B01              C1264           
Q_CAP_0402-1UF,6.3V,10%,EMPTY,A CH5101K1B01              C1265           

----------------

Q_CAP_0402-27PF  ,50V ,5% ,EMPA CH02706JB06              C103            
Q_CAP_0402-27PF  ,50V ,5% ,EMPA CH02706JB06              C104            

----------------

Q_CAP_0402-27PF  ,50V ,5% ,NPOA CH02706JB06              C1507           
Q_CAP_0402-27PF  ,50V ,5% ,NPOA CH02706JB06              C1508           

----------------

Q_CAP_0402-3300PF,50V,10%,EMPTA CH2336K1B12              PC1173_P0_3     
Q_CAP_0402-3300PF,50V,10%,EMPTA CH2336K1B12              PC1174_P0_4     

----------------

Q_CAP_0402-3300PF,50V,10%,X7R,A CH2336K1B12              C591            
Q_CAP_0402-3300PF,50V,10%,X7R,A CH2336K1B12              PC1193_P1_3     
Q_CAP_0402-3300PF,50V,10%,X7R,A CH2336K1B12              PC1194_P1_4     
Q_CAP_0402-3300PF,50V,10%,X7R,A CH2336K1B12              PC176           
Q_CAP_0402-3300PF,50V,10%,X7R,A CH2336K1B12              PC189_P0_1      
Q_CAP_0402-3300PF,50V,10%,X7R,A CH2336K1B12              PC190_P0_2      
Q_CAP_0402-3300PF,50V,10%,X7R,A CH2336K1B12              PC215           
Q_CAP_0402-3300PF,50V,10%,X7R,A CH2336K1B12              PC216           
Q_CAP_0402-3300PF,50V,10%,X7R,A CH2336K1B12              PC230_P0_8      
Q_CAP_0402-3300PF,50V,10%,X7R,A CH2336K1B12              PC231_P0_7      
Q_CAP_0402-3300PF,50V,10%,X7R,A CH2336K1B12              PC252_P0_6      
Q_CAP_0402-3300PF,50V,10%,X7R,A CH2336K1B12              PC253_P0_5      
Q_CAP_0402-3300PF,50V,10%,X7R,A CH2336K1B12              PC27            
Q_CAP_0402-3300PF,50V,10%,X7R,A CH2336K1B12              PC274_P0_4      
Q_CAP_0402-3300PF,50V,10%,X7R,A CH2336K1B12              PC275_P0_3      
Q_CAP_0402-3300PF,50V,10%,X7R,A CH2336K1B12              PC28            
Q_CAP_0402-3300PF,50V,10%,X7R,A CH2336K1B12              PC296_P0_2      
Q_CAP_0402-3300PF,50V,10%,X7R,A CH2336K1B12              PC297_P0_1      
Q_CAP_0402-3300PF,50V,10%,X7R,A CH2336K1B12              PC331           
Q_CAP_0402-3300PF,50V,10%,X7R,A CH2336K1B12              PC374           
Q_CAP_0402-3300PF,50V,10%,X7R,A CH2336K1B12              PC389           
Q_CAP_0402-3300PF,50V,10%,X7R,A CH2336K1B12              PC397_P1_1      
Q_CAP_0402-3300PF,50V,10%,X7R,A CH2336K1B12              PC398_P1_2      
Q_CAP_0402-3300PF,50V,10%,X7R,A CH2336K1B12              PC422           
Q_CAP_0402-3300PF,50V,10%,X7R,A CH2336K1B12              PC429           
Q_CAP_0402-3300PF,50V,10%,X7R,A CH2336K1B12              PC442_P1_1      
Q_CAP_0402-3300PF,50V,10%,X7R,A CH2336K1B12              PC443_P1_2      
Q_CAP_0402-3300PF,50V,10%,X7R,A CH2336K1B12              PC468           
Q_CAP_0402-3300PF,50V,10%,X7R,A CH2336K1B12              PC469           
Q_CAP_0402-3300PF,50V,10%,X7R,A CH2336K1B12              PC483_P1_8      
Q_CAP_0402-3300PF,50V,10%,X7R,A CH2336K1B12              PC484_P1_7      
Q_CAP_0402-3300PF,50V,10%,X7R,A CH2336K1B12              PC505_P1_6      
Q_CAP_0402-3300PF,50V,10%,X7R,A CH2336K1B12              PC506_P1_5      
Q_CAP_0402-3300PF,50V,10%,X7R,A CH2336K1B12              PC527_P1_4      
Q_CAP_0402-3300PF,50V,10%,X7R,A CH2336K1B12              PC528_P1_3      
Q_CAP_0402-3300PF,50V,10%,X7R,A CH2336K1B12              PC549           
Q_CAP_0402-3300PF,50V,10%,X7R,A CH2336K1B12              PC560_P1_2      
Q_CAP_0402-3300PF,50V,10%,X7R,A CH2336K1B12              PC561_P1_1      
Q_CAP_0402-3300PF,50V,10%,X7R,A CH2336K1B12              PC594           
Q_CAP_0402-3300PF,50V,10%,X7R,A CH2336K1B12              PC602_P0_1      
Q_CAP_0402-3300PF,50V,10%,X7R,A CH2336K1B12              PC603_P0_2      
Q_CAP_0402-3300PF,50V,10%,X7R,A CH2336K1B12              PC627           
Q_CAP_0402-3300PF,50V,10%,X7R,A CH2336K1B12              PC634           

----------------

Q_CAP_0402-4.7UF,6.3V,20%,X6S,A CH5471MEB01              PC224           
Q_CAP_0402-4.7UF,6.3V,20%,X6S,A CH5471MEB01              PC335           
Q_CAP_0402-4.7UF,6.3V,20%,X6S,A CH5471MEB01              PC392           
Q_CAP_0402-4.7UF,6.3V,20%,X6S,A CH5471MEB01              PC477           
Q_CAP_0402-4.7UF,6.3V,20%,X6S,A CH5471MEB01              PC553           
Q_CAP_0402-4.7UF,6.3V,20%,X6S,A CH5471MEB01              PC630           

----------------

Q_CAP_0402-470PF,50V,10%,X7R,TA CH14706KB18              PC222           
Q_CAP_0402-470PF,50V,10%,X7R,TA CH14706KB18              PC336           
Q_CAP_0402-470PF,50V,10%,X7R,TA CH14706KB18              PC393           
Q_CAP_0402-470PF,50V,10%,X7R,TA CH14706KB18              PC475           
Q_CAP_0402-470PF,50V,10%,X7R,TA CH14706KB18              PC554           
Q_CAP_0402-470PF,50V,10%,X7R,TA CH14706KB18              PC631           
Q_CAP_0402-470PF,50V,10%,X7R,TA CH14706KB18              PC1271          
Q_CAP_0402-470PF,50V,10%,X7R,TA CH14706KB18              PC1292          

----------------

Q_CAP_0402-47PF,50V,5%,NPO,TMPA CH04706JB01              PC1877          

----------------

Q_CAP_0402-680PF,50V,10%,X7R,TA CH16806KB17              PC237           
Q_CAP_0402-680PF,50V,10%,X7R,TA CH16806KB17              PC238           

----------------

Q_CAP_0805-22UF,4V,20%,EMPTY,TA CH622KMEA01              PC1185_P0_3     
Q_CAP_0805-22UF,4V,20%,EMPTY,TA CH622KMEA01              PC1186_P0_4     
Q_CAP_0805-22UF,4V,20%,EMPTY,TA CH622KMEA01              PC1187_P0_3     
Q_CAP_0805-22UF,4V,20%,EMPTY,TA CH622KMEA01              PC1188_P0_4     
Q_CAP_0805-22UF,4V,20%,EMPTY,TA CH622KMEA01              PC1255          
Q_CAP_0805-22UF,4V,20%,EMPTY,TA CH622KMEA01              PC1256          
Q_CAP_0805-22UF,4V,20%,EMPTY,TA CH622KMEA01              PC1257          

----------------

Q_CAP_0805-22UF,4V,20%,X6S,TMPA CH622KMEA01              PC1206_P1_3     
Q_CAP_0805-22UF,4V,20%,X6S,TMPA CH622KMEA01              PC1207_P1_4     
Q_CAP_0805-22UF,4V,20%,X6S,TMPA CH622KMEA01              PC1208_P1_3     
Q_CAP_0805-22UF,4V,20%,X6S,TMPA CH622KMEA01              PC1209_P1_4     
Q_CAP_0805-22UF,4V,20%,X6S,TMPA CH622KMEA01              PC184           
Q_CAP_0805-22UF,4V,20%,X6S,TMPA CH622KMEA01              PC186           
Q_CAP_0805-22UF,4V,20%,X6S,TMPA CH622KMEA01              PC202_P0_1      
Q_CAP_0805-22UF,4V,20%,X6S,TMPA CH622KMEA01              PC203_P0_2      
Q_CAP_0805-22UF,4V,20%,X6S,TMPA CH622KMEA01              PC204_P0_1      
Q_CAP_0805-22UF,4V,20%,X6S,TMPA CH622KMEA01              PC205_P0_2      
Q_CAP_0805-22UF,4V,20%,X6S,TMPA CH622KMEA01              PC244_P0_8      
Q_CAP_0805-22UF,4V,20%,X6S,TMPA CH622KMEA01              PC245_P0_7      
Q_CAP_0805-22UF,4V,20%,X6S,TMPA CH622KMEA01              PC246_P0_8      
Q_CAP_0805-22UF,4V,20%,X6S,TMPA CH622KMEA01              PC247_P0_7      
Q_CAP_0805-22UF,4V,20%,X6S,TMPA CH622KMEA01              PC266_P0_6      
Q_CAP_0805-22UF,4V,20%,X6S,TMPA CH622KMEA01              PC267_P0_5      
Q_CAP_0805-22UF,4V,20%,X6S,TMPA CH622KMEA01              PC268_P0_6      
Q_CAP_0805-22UF,4V,20%,X6S,TMPA CH622KMEA01              PC269_P0_5      
Q_CAP_0805-22UF,4V,20%,X6S,TMPA CH622KMEA01              PC288_P0_4      
Q_CAP_0805-22UF,4V,20%,X6S,TMPA CH622KMEA01              PC289_P0_3      
Q_CAP_0805-22UF,4V,20%,X6S,TMPA CH622KMEA01              PC290_P0_4      
Q_CAP_0805-22UF,4V,20%,X6S,TMPA CH622KMEA01              PC291_P0_3      
Q_CAP_0805-22UF,4V,20%,X6S,TMPA CH622KMEA01              PC311_P0_2      
Q_CAP_0805-22UF,4V,20%,X6S,TMPA CH622KMEA01              PC312_P0_1      
Q_CAP_0805-22UF,4V,20%,X6S,TMPA CH622KMEA01              PC313_P0_2      
Q_CAP_0805-22UF,4V,20%,X6S,TMPA CH622KMEA01              PC314_P0_1      
Q_CAP_0805-22UF,4V,20%,X6S,TMPA CH622KMEA01              PC381           
Q_CAP_0805-22UF,4V,20%,X6S,TMPA CH622KMEA01              PC382           
Q_CAP_0805-22UF,4V,20%,X6S,TMPA CH622KMEA01              PC410_P1_1      
Q_CAP_0805-22UF,4V,20%,X6S,TMPA CH622KMEA01              PC411_P1_2      
Q_CAP_0805-22UF,4V,20%,X6S,TMPA CH622KMEA01              PC412_P1_1      
Q_CAP_0805-22UF,4V,20%,X6S,TMPA CH622KMEA01              PC413_P1_2      
Q_CAP_0805-22UF,4V,20%,X6S,TMPA CH622KMEA01              PC435           
Q_CAP_0805-22UF,4V,20%,X6S,TMPA CH622KMEA01              PC437           
Q_CAP_0805-22UF,4V,20%,X6S,TMPA CH622KMEA01              PC1206          
Q_CAP_0805-22UF,4V,20%,X6S,TMPA CH622KMEA01              PC1207          
Q_CAP_0805-22UF,4V,20%,X6S,TMPA CH622KMEA01              PC1237          
Q_CAP_0805-22UF,4V,20%,X6S,TMPA CH622KMEA01              PC1238          
Q_CAP_0805-22UF,4V,20%,X6S,TMPA CH622KMEA01              PC1239          
Q_CAP_0805-22UF,4V,20%,X6S,TMPA CH622KMEA01              PC1240          
Q_CAP_0805-22UF,4V,20%,X6S,TMPA CH622KMEA01              PC1241          
Q_CAP_0805-22UF,4V,20%,X6S,TMPA CH622KMEA01              PC1268          
Q_CAP_0805-22UF,4V,20%,X6S,TMPA CH622KMEA01              PC1269          
Q_CAP_0805-22UF,4V,20%,X6S,TMPA CH622KMEA01              PC1270          
Q_CAP_0805-22UF,4V,20%,X6S,TMPA CH622KMEA01              PC1277          
Q_CAP_0805-22UF,4V,20%,X6S,TMPA CH622KMEA01              PC1278          
Q_CAP_0805-22UF,4V,20%,X6S,TMPA CH622KMEA01              PC1279          
Q_CAP_0805-22UF,4V,20%,X6S,TMPA CH622KMEA01              PC1285          
Q_CAP_0805-22UF,4V,20%,X6S,TMPA CH622KMEA01              PC1286          
Q_CAP_0805-22UF,4V,20%,X6S,TMPA CH622KMEA01              PC1287          
Q_CAP_0805-22UF,4V,20%,X6S,TMPA CH622KMEA01              PC455_P1_1      
Q_CAP_0805-22UF,4V,20%,X6S,TMPA CH622KMEA01              PC456_P1_2      
Q_CAP_0805-22UF,4V,20%,X6S,TMPA CH622KMEA01              PC457_P1_1      
Q_CAP_0805-22UF,4V,20%,X6S,TMPA CH622KMEA01              PC458_P1_2      
Q_CAP_0805-22UF,4V,20%,X6S,TMPA CH622KMEA01              PC497_P1_8      
Q_CAP_0805-22UF,4V,20%,X6S,TMPA CH622KMEA01              PC498_P1_7      
Q_CAP_0805-22UF,4V,20%,X6S,TMPA CH622KMEA01              PC499_P1_8      
Q_CAP_0805-22UF,4V,20%,X6S,TMPA CH622KMEA01              PC500_P1_7      
Q_CAP_0805-22UF,4V,20%,X6S,TMPA CH622KMEA01              PC519_P1_6      
Q_CAP_0805-22UF,4V,20%,X6S,TMPA CH622KMEA01              PC520_P1_5      
Q_CAP_0805-22UF,4V,20%,X6S,TMPA CH622KMEA01              PC521_P1_6      
Q_CAP_0805-22UF,4V,20%,X6S,TMPA CH622KMEA01              PC522_P1_5      
Q_CAP_0805-22UF,4V,20%,X6S,TMPA CH622KMEA01              PC541_P1_4      
Q_CAP_0805-22UF,4V,20%,X6S,TMPA CH622KMEA01              PC542_P1_3      
Q_CAP_0805-22UF,4V,20%,X6S,TMPA CH622KMEA01              PC543_P1_4      
Q_CAP_0805-22UF,4V,20%,X6S,TMPA CH622KMEA01              PC544_P1_3      
Q_CAP_0805-22UF,4V,20%,X6S,TMPA CH622KMEA01              PC575_P1_2      
Q_CAP_0805-22UF,4V,20%,X6S,TMPA CH622KMEA01              PC576_P1_1      
Q_CAP_0805-22UF,4V,20%,X6S,TMPA CH622KMEA01              PC577_P1_2      
Q_CAP_0805-22UF,4V,20%,X6S,TMPA CH622KMEA01              PC578_P1_1      
Q_CAP_0805-22UF,4V,20%,X6S,TMPA CH622KMEA01              PC615_P0_1      
Q_CAP_0805-22UF,4V,20%,X6S,TMPA CH622KMEA01              PC616_P0_2      
Q_CAP_0805-22UF,4V,20%,X6S,TMPA CH622KMEA01              PC617_P0_1      
Q_CAP_0805-22UF,4V,20%,X6S,TMPA CH622KMEA01              PC618_P0_2      
Q_CAP_0805-22UF,4V,20%,X6S,TMPA CH622KMEA01              PC641           
Q_CAP_0805-22UF,4V,20%,X6S,TMPA CH622KMEA01              PC642           

----------------

Q_CAP_0805-47UF,4V,20%,X6S,CH6A CH647KMEA00              C101            
Q_CAP_0805-47UF,4V,20%,X6S,CH6A CH647KMEA00              C212            
Q_CAP_0805-47UF,4V,20%,X6S,CH6A CH647KMEA00              C213            
Q_CAP_0805-47UF,4V,20%,X6S,CH6A CH647KMEA00              C214            
Q_CAP_0805-47UF,4V,20%,X6S,CH6A CH647KMEA00              C215            
Q_CAP_0805-47UF,4V,20%,X6S,CH6A CH647KMEA00              C216            
Q_CAP_0805-47UF,4V,20%,X6S,CH6A CH647KMEA00              C217            
Q_CAP_0805-47UF,4V,20%,X6S,CH6A CH647KMEA00              C218            
Q_CAP_0805-47UF,4V,20%,X6S,CH6A CH647KMEA00              C219            
Q_CAP_0805-47UF,4V,20%,X6S,CH6A CH647KMEA00              C220            
Q_CAP_0805-47UF,4V,20%,X6S,CH6A CH647KMEA00              C225            
Q_CAP_0805-47UF,4V,20%,X6S,CH6A CH647KMEA00              C230            
Q_CAP_0805-47UF,4V,20%,X6S,CH6A CH647KMEA00              C235            
Q_CAP_0805-47UF,4V,20%,X6S,CH6A CH647KMEA00              C240            
Q_CAP_0805-47UF,4V,20%,X6S,CH6A CH647KMEA00              C245            
Q_CAP_0805-47UF,4V,20%,X6S,CH6A CH647KMEA00              C250            
Q_CAP_0805-47UF,4V,20%,X6S,CH6A CH647KMEA00              C255            
Q_CAP_0805-47UF,4V,20%,X6S,CH6A CH647KMEA00              C260            
Q_CAP_0805-47UF,4V,20%,X6S,CH6A CH647KMEA00              C265            
Q_CAP_0805-47UF,4V,20%,X6S,CH6A CH647KMEA00              C270            
Q_CAP_0805-47UF,4V,20%,X6S,CH6A CH647KMEA00              C1243           
Q_CAP_0805-47UF,4V,20%,X6S,CH6A CH647KMEA00              C1244           
Q_CAP_0805-47UF,4V,20%,X6S,CH6A CH647KMEA00              C1245           
Q_CAP_0805-47UF,4V,20%,X6S,CH6A CH647KMEA00              C1246           
Q_CAP_0805-47UF,4V,20%,X6S,CH6A CH647KMEA00              C1247           
Q_CAP_0805-47UF,4V,20%,X6S,CH6A CH647KMEA00              C1248           
Q_CAP_0805-47UF,4V,20%,X6S,CH6A CH647KMEA00              C1249           
Q_CAP_0805-47UF,4V,20%,X6S,CH6A CH647KMEA00              C1258           
Q_CAP_0805-47UF,4V,20%,X6S,CH6A CH647KMEA00              C1259           
Q_CAP_0805-47UF,4V,20%,X6S,CH6A CH647KMEA00              C1272           
Q_CAP_0805-47UF,4V,20%,X6S,CH6A CH647KMEA00              C1273           
Q_CAP_0805-47UF,4V,20%,X6S,CH6A CH647KMEA00              PC1225          
Q_CAP_0805-47UF,4V,20%,X6S,CH6A CH647KMEA00              PC1226          

----------------

Q_CAP_C0201-0.22UF,6.3V,10%,X6A CH4221KEE00              C1436           
Q_CAP_C0201-0.22UF,6.3V,10%,X6A CH4221KEE00              C1437           

----------------

Q_CAP_C0402-0.047UF,25V,10%,X7A CH3474K1B04              C1316           
Q_CAP_C0402-0.047UF,25V,10%,X7A CH3474K1B04              C1503           
Q_CAP_C0402-0.047UF,25V,10%,X7A CH3474K1B04              C1504           
Q_CAP_C0402-0.047UF,25V,10%,X7A CH3474K1B04              C1510           
Q_CAP_C0402-0.047UF,25V,10%,X7A CH3474K1B04              C1511           
Q_CAP_C0402-0.047UF,25V,10%,X7A CH3474K1B04              C1596           

----------------

Q_CAP_C0402-100NF,50V,10%,EMPTA CH4106K1B01              PC1183_P0_4     
Q_CAP_C0402-100NF,50V,10%,EMPTA CH4106K1B01              PC223           
Q_CAP_C0402-100NF,50V,10%,EMPTA CH4106K1B01              PC334           
Q_CAP_C0402-100NF,50V,10%,EMPTA CH4106K1B01              PC391           
Q_CAP_C0402-100NF,50V,10%,EMPTA CH4106K1B01              PC476           
Q_CAP_C0402-100NF,50V,10%,EMPTA CH4106K1B01              PC552           
Q_CAP_C0402-100NF,50V,10%,EMPTA CH4106K1B01              PC629           
Q_CAP_C0402-100NF,50V,10%,EMPTA CH4106K1B01              PC1177          
Q_CAP_C0402-100NF,50V,10%,EMPTA CH4106K1B01              PC1178          

----------------

Q_CAP_C0402-100NF,50V,10%,X7R,A CH4106K1B01              C179            
Q_CAP_C0402-100NF,50V,10%,X7R,A CH4106K1B01              C575            
Q_CAP_C0402-100NF,50V,10%,X7R,A CH4106K1B01              C582            
Q_CAP_C0402-100NF,50V,10%,X7R,A CH4106K1B01              C1042           
Q_CAP_C0402-100NF,50V,10%,X7R,A CH4106K1B01              C1172           
Q_CAP_C0402-100NF,50V,10%,X7R,A CH4106K1B01              C1227           
Q_CAP_C0402-100NF,50V,10%,X7R,A CH4106K1B01              C1326           
Q_CAP_C0402-100NF,50V,10%,X7R,A CH4106K1B01              C1332           
Q_CAP_C0402-100NF,50V,10%,X7R,A CH4106K1B01              C1339           
Q_CAP_C0402-100NF,50V,10%,X7R,A CH4106K1B01              C1480           
Q_CAP_C0402-100NF,50V,10%,X7R,A CH4106K1B01              C1484           
Q_CAP_C0402-100NF,50V,10%,X7R,A CH4106K1B01              C1582           
Q_CAP_C0402-100NF,50V,10%,X7R,A CH4106K1B01              C1583           
Q_CAP_C0402-100NF,50V,10%,X7R,A CH4106K1B01              C1584           
Q_CAP_C0402-100NF,50V,10%,X7R,A CH4106K1B01              C1586           
Q_CAP_C0402-100NF,50V,10%,X7R,A CH4106K1B01              PC1203_P1_4     
Q_CAP_C0402-100NF,50V,10%,X7R,A CH4106K1B01              PC178           
Q_CAP_C0402-100NF,50V,10%,X7R,A CH4106K1B01              PC181           
Q_CAP_C0402-100NF,50V,10%,X7R,A CH4106K1B01              PC193           
Q_CAP_C0402-100NF,50V,10%,X7R,A CH4106K1B01              PC194           
Q_CAP_C0402-100NF,50V,10%,X7R,A CH4106K1B01              PC199_P0_1      
Q_CAP_C0402-100NF,50V,10%,X7R,A CH4106K1B01              PC234           
Q_CAP_C0402-100NF,50V,10%,X7R,A CH4106K1B01              PC235           
Q_CAP_C0402-100NF,50V,10%,X7R,A CH4106K1B01              PC256           
Q_CAP_C0402-100NF,50V,10%,X7R,A CH4106K1B01              PC257           
Q_CAP_C0402-100NF,50V,10%,X7R,A CH4106K1B01              PC278           
Q_CAP_C0402-100NF,50V,10%,X7R,A CH4106K1B01              PC279           
Q_CAP_C0402-100NF,50V,10%,X7R,A CH4106K1B01              PC300           
Q_CAP_C0402-100NF,50V,10%,X7R,A CH4106K1B01              PC301           
Q_CAP_C0402-100NF,50V,10%,X7R,A CH4106K1B01              PC308_P0_1      
Q_CAP_C0402-100NF,50V,10%,X7R,A CH4106K1B01              PC328           
Q_CAP_C0402-100NF,50V,10%,X7R,A CH4106K1B01              PC376           
Q_CAP_C0402-100NF,50V,10%,X7R,A CH4106K1B01              PC379           
Q_CAP_C0402-100NF,50V,10%,X7R,A CH4106K1B01              PC401           
Q_CAP_C0402-100NF,50V,10%,X7R,A CH4106K1B01              PC402           
Q_CAP_C0402-100NF,50V,10%,X7R,A CH4106K1B01              PC431           
Q_CAP_C0402-100NF,50V,10%,X7R,A CH4106K1B01              PC434           
Q_CAP_C0402-100NF,50V,10%,X7R,A CH4106K1B01              PC446           
Q_CAP_C0402-100NF,50V,10%,X7R,A CH4106K1B01              PC447           
Q_CAP_C0402-100NF,50V,10%,X7R,A CH4106K1B01              PC452_P1_1      
Q_CAP_C0402-100NF,50V,10%,X7R,A CH4106K1B01              PC487           
Q_CAP_C0402-100NF,50V,10%,X7R,A CH4106K1B01              PC488           
Q_CAP_C0402-100NF,50V,10%,X7R,A CH4106K1B01              PC509           
Q_CAP_C0402-100NF,50V,10%,X7R,A CH4106K1B01              PC510           
Q_CAP_C0402-100NF,50V,10%,X7R,A CH4106K1B01              PC531           
Q_CAP_C0402-100NF,50V,10%,X7R,A CH4106K1B01              PC532           
Q_CAP_C0402-100NF,50V,10%,X7R,A CH4106K1B01              PC546           
Q_CAP_C0402-100NF,50V,10%,X7R,A CH4106K1B01              PC564           
Q_CAP_C0402-100NF,50V,10%,X7R,A CH4106K1B01              PC565           
Q_CAP_C0402-100NF,50V,10%,X7R,A CH4106K1B01              PC606           
Q_CAP_C0402-100NF,50V,10%,X7R,A CH4106K1B01              PC607           
Q_CAP_C0402-100NF,50V,10%,X7R,A CH4106K1B01              PC636           
Q_CAP_C0402-100NF,50V,10%,X7R,A CH4106K1B01              PC639           
Q_CAP_C0402-100NF,50V,10%,X7R,A CH4106K1B01              PC1197          
Q_CAP_C0402-100NF,50V,10%,X7R,A CH4106K1B01              PC1198          
Q_CAP_C0402-100NF,50V,10%,X7R,A CH4106K1B01              PC1234          
Q_CAP_C0402-100NF,50V,10%,X7R,A CH4106K1B01              PC1236          
Q_CAP_C0402-100NF,50V,10%,X7R,A CH4106K1B01              PC1274          
Q_CAP_C0402-100NF,50V,10%,X7R,A CH4106K1B01              PC1276          
Q_CAP_C0402-100NF,50V,10%,X7R,A CH4106K1B01              PC1282          
Q_CAP_C0402-100NF,50V,10%,X7R,A CH4106K1B01              PC1284          
Q_CAP_C0402-100NF,50V,10%,X7R,A CH4106K1B01              PC572_P1_1      
Q_CAP_C0402-100NF,50V,10%,X7R,A CH4106K1B01              PC612_P0_1      
Q_CAP_C0402-100NF,50V,10%,X7R,A CH4106K1B01              PC621_P1_1      

----------------

Q_CAP_C0402-10UF,6.3V,20%,X6S,A CH6101MEB01              C1              
Q_CAP_C0402-10UF,6.3V,20%,X6S,A CH6101MEB01              C71             
Q_CAP_C0402-10UF,6.3V,20%,X6S,A CH6101MEB01              C1203           
Q_CAP_C0402-10UF,6.3V,20%,X6S,A CH6101MEB01              C1205           
Q_CAP_C0402-10UF,6.3V,20%,X6S,A CH6101MEB01              C1206           
Q_CAP_C0402-10UF,6.3V,20%,X6S,A CH6101MEB01              C1207           
Q_CAP_C0402-10UF,6.3V,20%,X6S,A CH6101MEB01              C1210           
Q_CAP_C0402-10UF,6.3V,20%,X6S,A CH6101MEB01              C1228           
Q_CAP_C0402-10UF,6.3V,20%,X6S,A CH6101MEB01              C1231           
Q_CAP_C0402-10UF,6.3V,20%,X6S,A CH6101MEB01              C1262           
Q_CAP_C0402-10UF,6.3V,20%,X6S,A CH6101MEB01              C1263           
Q_CAP_C0402-10UF,6.3V,20%,X6S,A CH6101MEB01              C1266           
Q_CAP_C0402-10UF,6.3V,20%,X6S,A CH6101MEB01              C2443           
Q_CAP_C0402-10UF,6.3V,20%,X6S,A CH6101MEB01              PC1336          

----------------

Q_CAP_C0402-1UF,16V,10%,EMPTY,A CH5103KEB01              PC1175_P0_3     
Q_CAP_C0402-1UF,16V,10%,EMPTY,A CH5103KEB01              PC1176_P0_4     
Q_CAP_C0402-1UF,16V,10%,EMPTY,A CH5103KEB01              PC1183_P0_3     

----------------

Q_CAP_C0402-1UF,16V,10%,X6S,CHA CH5103KEB01              C583            
Q_CAP_C0402-1UF,16V,10%,X6S,CHA CH5103KEB01              C589            
Q_CAP_C0402-1UF,16V,10%,X6S,CHA CH5103KEB01              PC1195_P1_3     
Q_CAP_C0402-1UF,16V,10%,X6S,CHA CH5103KEB01              PC1196_P1_4     
Q_CAP_C0402-1UF,16V,10%,X6S,CHA CH5103KEB01              PC1204_P1_3     
Q_CAP_C0402-1UF,16V,10%,X6S,CHA CH5103KEB01              PC177           
Q_CAP_C0402-1UF,16V,10%,X6S,CHA CH5103KEB01              PC191_P0_1      
Q_CAP_C0402-1UF,16V,10%,X6S,CHA CH5103KEB01              PC192_P0_2      
Q_CAP_C0402-1UF,16V,10%,X6S,CHA CH5103KEB01              PC225           
Q_CAP_C0402-1UF,16V,10%,X6S,CHA CH5103KEB01              PC232_P0_8      
Q_CAP_C0402-1UF,16V,10%,X6S,CHA CH5103KEB01              PC233_P0_7      
Q_CAP_C0402-1UF,16V,10%,X6S,CHA CH5103KEB01              PC242_P0_8      
Q_CAP_C0402-1UF,16V,10%,X6S,CHA CH5103KEB01              PC243_P0_7      
Q_CAP_C0402-1UF,16V,10%,X6S,CHA CH5103KEB01              PC254_P0_6      
Q_CAP_C0402-1UF,16V,10%,X6S,CHA CH5103KEB01              PC255_P0_5      
Q_CAP_C0402-1UF,16V,10%,X6S,CHA CH5103KEB01              PC276_P0_4      
Q_CAP_C0402-1UF,16V,10%,X6S,CHA CH5103KEB01              PC277_P0_3      
Q_CAP_C0402-1UF,16V,10%,X6S,CHA CH5103KEB01              PC298_P0_2      
Q_CAP_C0402-1UF,16V,10%,X6S,CHA CH5103KEB01              PC299_P0_1      
Q_CAP_C0402-1UF,16V,10%,X6S,CHA CH5103KEB01              PC310_P0_1      
Q_CAP_C0402-1UF,16V,10%,X6S,CHA CH5103KEB01              PC337           
Q_CAP_C0402-1UF,16V,10%,X6S,CHA CH5103KEB01              PC375           
Q_CAP_C0402-1UF,16V,10%,X6S,CHA CH5103KEB01              PC394           
Q_CAP_C0402-1UF,16V,10%,X6S,CHA CH5103KEB01              PC430           
Q_CAP_C0402-1UF,16V,10%,X6S,CHA CH5103KEB01              PC478           
Q_CAP_C0402-1UF,16V,10%,X6S,CHA CH5103KEB01              PC1173          
Q_CAP_C0402-1UF,16V,10%,X6S,CHA CH5103KEB01              PC1193          
Q_CAP_C0402-1UF,16V,10%,X6S,CHA CH5103KEB01              PC1194          
Q_CAP_C0402-1UF,16V,10%,X6S,CHA CH5103KEB01              PC1196          
Q_CAP_C0402-1UF,16V,10%,X6S,CHA CH5103KEB01              PC1289          
Q_CAP_C0402-1UF,16V,10%,X6S,CHA CH5103KEB01              PC1372          
Q_CAP_C0402-1UF,16V,10%,X6S,CHA CH5103KEB01              PC399_P1_1      
Q_CAP_C0402-1UF,16V,10%,X6S,CHA CH5103KEB01              PC400_P1_2      
Q_CAP_C0402-1UF,16V,10%,X6S,CHA CH5103KEB01              PC408_P1_2      
Q_CAP_C0402-1UF,16V,10%,X6S,CHA CH5103KEB01              PC444_P1_1      
Q_CAP_C0402-1UF,16V,10%,X6S,CHA CH5103KEB01              PC445_P1_2      
Q_CAP_C0402-1UF,16V,10%,X6S,CHA CH5103KEB01              PC485_P1_8      
Q_CAP_C0402-1UF,16V,10%,X6S,CHA CH5103KEB01              PC486_P1_7      
Q_CAP_C0402-1UF,16V,10%,X6S,CHA CH5103KEB01              PC495_P1_8      
Q_CAP_C0402-1UF,16V,10%,X6S,CHA CH5103KEB01              PC496_P1_7      
Q_CAP_C0402-1UF,16V,10%,X6S,CHA CH5103KEB01              PC507_P1_6      
Q_CAP_C0402-1UF,16V,10%,X6S,CHA CH5103KEB01              PC508_P1_5      
Q_CAP_C0402-1UF,16V,10%,X6S,CHA CH5103KEB01              PC529_P1_4      
Q_CAP_C0402-1UF,16V,10%,X6S,CHA CH5103KEB01              PC530_P1_3      
Q_CAP_C0402-1UF,16V,10%,X6S,CHA CH5103KEB01              PC555           
Q_CAP_C0402-1UF,16V,10%,X6S,CHA CH5103KEB01              PC562_P1_2      
Q_CAP_C0402-1UF,16V,10%,X6S,CHA CH5103KEB01              PC563_P1_1      
Q_CAP_C0402-1UF,16V,10%,X6S,CHA CH5103KEB01              PC574_P1_1      
Q_CAP_C0402-1UF,16V,10%,X6S,CHA CH5103KEB01              PC604_P0_1      
Q_CAP_C0402-1UF,16V,10%,X6S,CHA CH5103KEB01              PC605_P0_2      
Q_CAP_C0402-1UF,16V,10%,X6S,CHA CH5103KEB01              PC613_P0_2      
Q_CAP_C0402-1UF,16V,10%,X6S,CHA CH5103KEB01              PC632           
Q_CAP_C0402-1UF,16V,10%,X6S,CHA CH5103KEB01              PC635           
Q_CAP_C0402-1UF,16V,10%,X6S,CHA CH5103KEB01              PC813           
Q_CAP_C0402-1UF,16V,10%,X6S,CHA CH5103KEB01              PC814           

----------------

Q_CAP_C0402-1UF,25V,10%,EMPTY,A CH5104KEB02              C613            
Q_CAP_C0402-1UF,25V,10%,EMPTY,A CH5104KEB02              C614            
Q_CAP_C0402-1UF,25V,10%,EMPTY,A CH5104KEB02              C615            
Q_CAP_C0402-1UF,25V,10%,EMPTY,A CH5104KEB02              C616            
Q_CAP_C0402-1UF,25V,10%,EMPTY,A CH5104KEB02              C621            
Q_CAP_C0402-1UF,25V,10%,EMPTY,A CH5104KEB02              C622            
Q_CAP_C0402-1UF,25V,10%,EMPTY,A CH5104KEB02              C623            
Q_CAP_C0402-1UF,25V,10%,EMPTY,A CH5104KEB02              C624            
Q_CAP_C0402-1UF,25V,10%,EMPTY,A CH5104KEB02              C1318           
Q_CAP_C0402-1UF,25V,10%,EMPTY,A CH5104KEB02              C1581           
Q_CAP_C0402-1UF,25V,10%,EMPTY,A CH5104KEB02              C1587           
Q_CAP_C0402-1UF,25V,10%,EMPTY,A CH5104KEB02              PC2643          

----------------

Q_CAP_C0402-1UF,25V,10%,X6S,CHA CH5104KEB02              C109            
Q_CAP_C0402-1UF,25V,10%,X6S,CHA CH5104KEB02              C131            
Q_CAP_C0402-1UF,25V,10%,X6S,CHA CH5104KEB02              C137            
Q_CAP_C0402-1UF,25V,10%,X6S,CHA CH5104KEB02              C541            
Q_CAP_C0402-1UF,25V,10%,X6S,CHA CH5104KEB02              C542            
Q_CAP_C0402-1UF,25V,10%,X6S,CHA CH5104KEB02              C545            
Q_CAP_C0402-1UF,25V,10%,X6S,CHA CH5104KEB02              C546            
Q_CAP_C0402-1UF,25V,10%,X6S,CHA CH5104KEB02              C547            
Q_CAP_C0402-1UF,25V,10%,X6S,CHA CH5104KEB02              C550            
Q_CAP_C0402-1UF,25V,10%,X6S,CHA CH5104KEB02              C551            
Q_CAP_C0402-1UF,25V,10%,X6S,CHA CH5104KEB02              C605            
Q_CAP_C0402-1UF,25V,10%,X6S,CHA CH5104KEB02              C606            
Q_CAP_C0402-1UF,25V,10%,X6S,CHA CH5104KEB02              C610            
Q_CAP_C0402-1UF,25V,10%,X6S,CHA CH5104KEB02              C611            
Q_CAP_C0402-1UF,25V,10%,X6S,CHA CH5104KEB02              C1177           
Q_CAP_C0402-1UF,25V,10%,X6S,CHA CH5104KEB02              C1289           
Q_CAP_C0402-1UF,25V,10%,X6S,CHA CH5104KEB02              C1290           
Q_CAP_C0402-1UF,25V,10%,X6S,CHA CH5104KEB02              C1291           
Q_CAP_C0402-1UF,25V,10%,X6S,CHA CH5104KEB02              C1293           
Q_CAP_C0402-1UF,25V,10%,X6S,CHA CH5104KEB02              C1311           
Q_CAP_C0402-1UF,25V,10%,X6S,CHA CH5104KEB02              C1312           
Q_CAP_C0402-1UF,25V,10%,X6S,CHA CH5104KEB02              C1315           
Q_CAP_C0402-1UF,25V,10%,X6S,CHA CH5104KEB02              C1319           
Q_CAP_C0402-1UF,25V,10%,X6S,CHA CH5104KEB02              C1605           
Q_CAP_C0402-1UF,25V,10%,X6S,CHA CH5104KEB02              PC113           
Q_CAP_C0402-1UF,25V,10%,X6S,CHA CH5104KEB02              PC644           
Q_CAP_C0402-1UF,25V,10%,X6S,CHA CH5104KEB02              PC1642          
Q_CAP_C0402-1UF,25V,10%,X6S,CHA CH5104KEB02              PC1848          
Q_CAP_C0402-1UF,25V,10%,X6S,CHA CH5104KEB02              PC2221          
Q_CAP_C0402-1UF,25V,10%,X6S,CHA CH5104KEB02              PC2222          

----------------

Q_CAP_C0402-2.2UF,10V,10%,EMPTA CH5222KEB01              PC1171          
Q_CAP_C0402-2.2UF,10V,10%,EMPTA CH5222KEB01              PC1172          
Q_CAP_C0402-2.2UF,10V,10%,EMPTA CH5222KEB01              PC1213_P0_3     
Q_CAP_C0402-2.2UF,10V,10%,EMPTA CH5222KEB01              PC1214_P0_4     

----------------

Q_CAP_C0402-2.2UF,10V,10%,X6S,A CH5222KEB01              C1183           
Q_CAP_C0402-2.2UF,10V,10%,X6S,A CH5222KEB01              C1189           
Q_CAP_C0402-2.2UF,10V,10%,X6S,A CH5222KEB01              C1200           
Q_CAP_C0402-2.2UF,10V,10%,X6S,A CH5222KEB01              C1204           
Q_CAP_C0402-2.2UF,10V,10%,X6S,A CH5222KEB01              C1214           
Q_CAP_C0402-2.2UF,10V,10%,X6S,A CH5222KEB01              C1242           
Q_CAP_C0402-2.2UF,10V,10%,X6S,A CH5222KEB01              PC1211_P0_1     
Q_CAP_C0402-2.2UF,10V,10%,X6S,A CH5222KEB01              PC1212_P0_2     
Q_CAP_C0402-2.2UF,10V,10%,X6S,A CH5222KEB01              PC1242_P1_1     
Q_CAP_C0402-2.2UF,10V,10%,X6S,A CH5222KEB01              PC1243_P1_2     
Q_CAP_C0402-2.2UF,10V,10%,X6S,A CH5222KEB01              PC1244_P1_3     
Q_CAP_C0402-2.2UF,10V,10%,X6S,A CH5222KEB01              PC1245_P1_4     
Q_CAP_C0402-2.2UF,10V,10%,X6S,A CH5222KEB01              PC175           
Q_CAP_C0402-2.2UF,10V,10%,X6S,A CH5222KEB01              PC187           
Q_CAP_C0402-2.2UF,10V,10%,X6S,A CH5222KEB01              PC188           
Q_CAP_C0402-2.2UF,10V,10%,X6S,A CH5222KEB01              PC226           
Q_CAP_C0402-2.2UF,10V,10%,X6S,A CH5222KEB01              PC227           
Q_CAP_C0402-2.2UF,10V,10%,X6S,A CH5222KEB01              PC228_P0_8      
Q_CAP_C0402-2.2UF,10V,10%,X6S,A CH5222KEB01              PC229_P0_7      
Q_CAP_C0402-2.2UF,10V,10%,X6S,A CH5222KEB01              PC248           
Q_CAP_C0402-2.2UF,10V,10%,X6S,A CH5222KEB01              PC249           
Q_CAP_C0402-2.2UF,10V,10%,X6S,A CH5222KEB01              PC250_P0_6      
Q_CAP_C0402-2.2UF,10V,10%,X6S,A CH5222KEB01              PC251_P0_5      
Q_CAP_C0402-2.2UF,10V,10%,X6S,A CH5222KEB01              PC270           
Q_CAP_C0402-2.2UF,10V,10%,X6S,A CH5222KEB01              PC271           
Q_CAP_C0402-2.2UF,10V,10%,X6S,A CH5222KEB01              PC272_P0_4      
Q_CAP_C0402-2.2UF,10V,10%,X6S,A CH5222KEB01              PC273_P0_3      
Q_CAP_C0402-2.2UF,10V,10%,X6S,A CH5222KEB01              PC292           
Q_CAP_C0402-2.2UF,10V,10%,X6S,A CH5222KEB01              PC293           
Q_CAP_C0402-2.2UF,10V,10%,X6S,A CH5222KEB01              PC294_P0_2      
Q_CAP_C0402-2.2UF,10V,10%,X6S,A CH5222KEB01              PC295_P0_1      
Q_CAP_C0402-2.2UF,10V,10%,X6S,A CH5222KEB01              PC373           
Q_CAP_C0402-2.2UF,10V,10%,X6S,A CH5222KEB01              PC395           
Q_CAP_C0402-2.2UF,10V,10%,X6S,A CH5222KEB01              PC396           
Q_CAP_C0402-2.2UF,10V,10%,X6S,A CH5222KEB01              PC428           
Q_CAP_C0402-2.2UF,10V,10%,X6S,A CH5222KEB01              PC440           
Q_CAP_C0402-2.2UF,10V,10%,X6S,A CH5222KEB01              PC441           
Q_CAP_C0402-2.2UF,10V,10%,X6S,A CH5222KEB01              PC479           
Q_CAP_C0402-2.2UF,10V,10%,X6S,A CH5222KEB01              PC480           
Q_CAP_C0402-2.2UF,10V,10%,X6S,A CH5222KEB01              PC481_P1_8      
Q_CAP_C0402-2.2UF,10V,10%,X6S,A CH5222KEB01              PC482_P1_7      
Q_CAP_C0402-2.2UF,10V,10%,X6S,A CH5222KEB01              PC501           
Q_CAP_C0402-2.2UF,10V,10%,X6S,A CH5222KEB01              PC502           
Q_CAP_C0402-2.2UF,10V,10%,X6S,A CH5222KEB01              PC503_P1_6      
Q_CAP_C0402-2.2UF,10V,10%,X6S,A CH5222KEB01              PC504_P1_5      
Q_CAP_C0402-2.2UF,10V,10%,X6S,A CH5222KEB01              PC523           
Q_CAP_C0402-2.2UF,10V,10%,X6S,A CH5222KEB01              PC524           
Q_CAP_C0402-2.2UF,10V,10%,X6S,A CH5222KEB01              PC525_P1_4      
Q_CAP_C0402-2.2UF,10V,10%,X6S,A CH5222KEB01              PC526_P1_3      
Q_CAP_C0402-2.2UF,10V,10%,X6S,A CH5222KEB01              PC556           
Q_CAP_C0402-2.2UF,10V,10%,X6S,A CH5222KEB01              PC557           
Q_CAP_C0402-2.2UF,10V,10%,X6S,A CH5222KEB01              PC1191          
Q_CAP_C0402-2.2UF,10V,10%,X6S,A CH5222KEB01              PC1192          
Q_CAP_C0402-2.2UF,10V,10%,X6S,A CH5222KEB01              PC558_P1_2      
Q_CAP_C0402-2.2UF,10V,10%,X6S,A CH5222KEB01              PC559_P1_1      
Q_CAP_C0402-2.2UF,10V,10%,X6S,A CH5222KEB01              PC600           
Q_CAP_C0402-2.2UF,10V,10%,X6S,A CH5222KEB01              PC601           
Q_CAP_C0402-2.2UF,10V,10%,X6S,A CH5222KEB01              PC633           

----------------

Q_CAP_C0402-2.2UF,6.3V,20%,EMPA CH5221MEB00              C1115           

----------------

Q_CAP_C0402-2.2UF,6.3V,20%,X6SA CH5221MEB00              C2              
Q_CAP_C0402-2.2UF,6.3V,20%,X6SA CH5221MEB00              C5              
Q_CAP_C0402-2.2UF,6.3V,20%,X6SA CH5221MEB00              C8              
Q_CAP_C0402-2.2UF,6.3V,20%,X6SA CH5221MEB00              C11             
Q_CAP_C0402-2.2UF,6.3V,20%,X6SA CH5221MEB00              C14             
Q_CAP_C0402-2.2UF,6.3V,20%,X6SA CH5221MEB00              C17             
Q_CAP_C0402-2.2UF,6.3V,20%,X6SA CH5221MEB00              C20             
Q_CAP_C0402-2.2UF,6.3V,20%,X6SA CH5221MEB00              C23             
Q_CAP_C0402-2.2UF,6.3V,20%,X6SA CH5221MEB00              C26             
Q_CAP_C0402-2.2UF,6.3V,20%,X6SA CH5221MEB00              C29             
Q_CAP_C0402-2.2UF,6.3V,20%,X6SA CH5221MEB00              C32             
Q_CAP_C0402-2.2UF,6.3V,20%,X6SA CH5221MEB00              C35             
Q_CAP_C0402-2.2UF,6.3V,20%,X6SA CH5221MEB00              C38             
Q_CAP_C0402-2.2UF,6.3V,20%,X6SA CH5221MEB00              C41             
Q_CAP_C0402-2.2UF,6.3V,20%,X6SA CH5221MEB00              C44             
Q_CAP_C0402-2.2UF,6.3V,20%,X6SA CH5221MEB00              C47             
Q_CAP_C0402-2.2UF,6.3V,20%,X6SA CH5221MEB00              C50             
Q_CAP_C0402-2.2UF,6.3V,20%,X6SA CH5221MEB00              C53             
Q_CAP_C0402-2.2UF,6.3V,20%,X6SA CH5221MEB00              C56             
Q_CAP_C0402-2.2UF,6.3V,20%,X6SA CH5221MEB00              C59             
Q_CAP_C0402-2.2UF,6.3V,20%,X6SA CH5221MEB00              C62             
Q_CAP_C0402-2.2UF,6.3V,20%,X6SA CH5221MEB00              C65             
Q_CAP_C0402-2.2UF,6.3V,20%,X6SA CH5221MEB00              C68             
Q_CAP_C0402-2.2UF,6.3V,20%,X6SA CH5221MEB00              C72             
Q_CAP_C0402-2.2UF,6.3V,20%,X6SA CH5221MEB00              C75             
Q_CAP_C0402-2.2UF,6.3V,20%,X6SA CH5221MEB00              C78             
Q_CAP_C0402-2.2UF,6.3V,20%,X6SA CH5221MEB00              C81             
Q_CAP_C0402-2.2UF,6.3V,20%,X6SA CH5221MEB00              C84             
Q_CAP_C0402-2.2UF,6.3V,20%,X6SA CH5221MEB00              C87             
Q_CAP_C0402-2.2UF,6.3V,20%,X6SA CH5221MEB00              C90             
Q_CAP_C0402-2.2UF,6.3V,20%,X6SA CH5221MEB00              C93             
Q_CAP_C0402-2.2UF,6.3V,20%,X6SA CH5221MEB00              C96             

----------------

Q_CAP_C0402-22UF,4V,20%,X6S,CHA CH622KMEB02              C221            
Q_CAP_C0402-22UF,4V,20%,X6S,CHA CH622KMEB02              C222            
Q_CAP_C0402-22UF,4V,20%,X6S,CHA CH622KMEB02              C223            
Q_CAP_C0402-22UF,4V,20%,X6S,CHA CH622KMEB02              C224            
Q_CAP_C0402-22UF,4V,20%,X6S,CHA CH622KMEB02              C226            
Q_CAP_C0402-22UF,4V,20%,X6S,CHA CH622KMEB02              C227            
Q_CAP_C0402-22UF,4V,20%,X6S,CHA CH622KMEB02              C228            
Q_CAP_C0402-22UF,4V,20%,X6S,CHA CH622KMEB02              C229            
Q_CAP_C0402-22UF,4V,20%,X6S,CHA CH622KMEB02              C231            
Q_CAP_C0402-22UF,4V,20%,X6S,CHA CH622KMEB02              C232            
Q_CAP_C0402-22UF,4V,20%,X6S,CHA CH622KMEB02              C233            
Q_CAP_C0402-22UF,4V,20%,X6S,CHA CH622KMEB02              C234            
Q_CAP_C0402-22UF,4V,20%,X6S,CHA CH622KMEB02              C236            
Q_CAP_C0402-22UF,4V,20%,X6S,CHA CH622KMEB02              C237            
Q_CAP_C0402-22UF,4V,20%,X6S,CHA CH622KMEB02              C238            
Q_CAP_C0402-22UF,4V,20%,X6S,CHA CH622KMEB02              C239            
Q_CAP_C0402-22UF,4V,20%,X6S,CHA CH622KMEB02              C241            
Q_CAP_C0402-22UF,4V,20%,X6S,CHA CH622KMEB02              C242            
Q_CAP_C0402-22UF,4V,20%,X6S,CHA CH622KMEB02              C243            
Q_CAP_C0402-22UF,4V,20%,X6S,CHA CH622KMEB02              C244            
Q_CAP_C0402-22UF,4V,20%,X6S,CHA CH622KMEB02              C246            
Q_CAP_C0402-22UF,4V,20%,X6S,CHA CH622KMEB02              C247            
Q_CAP_C0402-22UF,4V,20%,X6S,CHA CH622KMEB02              C248            
Q_CAP_C0402-22UF,4V,20%,X6S,CHA CH622KMEB02              C249            
Q_CAP_C0402-22UF,4V,20%,X6S,CHA CH622KMEB02              C251            
Q_CAP_C0402-22UF,4V,20%,X6S,CHA CH622KMEB02              C252            
Q_CAP_C0402-22UF,4V,20%,X6S,CHA CH622KMEB02              C253            
Q_CAP_C0402-22UF,4V,20%,X6S,CHA CH622KMEB02              C254            
Q_CAP_C0402-22UF,4V,20%,X6S,CHA CH622KMEB02              C256            
Q_CAP_C0402-22UF,4V,20%,X6S,CHA CH622KMEB02              C257            
Q_CAP_C0402-22UF,4V,20%,X6S,CHA CH622KMEB02              C258            
Q_CAP_C0402-22UF,4V,20%,X6S,CHA CH622KMEB02              C259            
Q_CAP_C0402-22UF,4V,20%,X6S,CHA CH622KMEB02              C261            
Q_CAP_C0402-22UF,4V,20%,X6S,CHA CH622KMEB02              C262            
Q_CAP_C0402-22UF,4V,20%,X6S,CHA CH622KMEB02              C263            
Q_CAP_C0402-22UF,4V,20%,X6S,CHA CH622KMEB02              C264            
Q_CAP_C0402-22UF,4V,20%,X6S,CHA CH622KMEB02              C266            
Q_CAP_C0402-22UF,4V,20%,X6S,CHA CH622KMEB02              C267            
Q_CAP_C0402-22UF,4V,20%,X6S,CHA CH622KMEB02              C268            
Q_CAP_C0402-22UF,4V,20%,X6S,CHA CH622KMEB02              C269            
Q_CAP_C0402-22UF,4V,20%,X6S,CHA CH622KMEB02              C271            
Q_CAP_C0402-22UF,4V,20%,X6S,CHA CH622KMEB02              C272            
Q_CAP_C0402-22UF,4V,20%,X6S,CHA CH622KMEB02              C273            
Q_CAP_C0402-22UF,4V,20%,X6S,CHA CH622KMEB02              C274            
Q_CAP_C0402-22UF,4V,20%,X6S,CHA CH622KMEB02              C275            
Q_CAP_C0402-22UF,4V,20%,X6S,CHA CH622KMEB02              C276            
Q_CAP_C0402-22UF,4V,20%,X6S,CHA CH622KMEB02              C277            
Q_CAP_C0402-22UF,4V,20%,X6S,CHA CH622KMEB02              C278            
Q_CAP_C0402-22UF,4V,20%,X6S,CHA CH622KMEB02              C279            
Q_CAP_C0402-22UF,4V,20%,X6S,CHA CH622KMEB02              C280            
Q_CAP_C0402-22UF,4V,20%,X6S,CHA CH622KMEB02              C281            
Q_CAP_C0402-22UF,4V,20%,X6S,CHA CH622KMEB02              C282            
Q_CAP_C0402-22UF,4V,20%,X6S,CHA CH622KMEB02              C283            
Q_CAP_C0402-22UF,4V,20%,X6S,CHA CH622KMEB02              C284            
Q_CAP_C0402-22UF,4V,20%,X6S,CHA CH622KMEB02              C285            
Q_CAP_C0402-22UF,4V,20%,X6S,CHA CH622KMEB02              C286            
Q_CAP_C0402-22UF,4V,20%,X6S,CHA CH622KMEB02              C287            
Q_CAP_C0402-22UF,4V,20%,X6S,CHA CH622KMEB02              C288            
Q_CAP_C0402-22UF,4V,20%,X6S,CHA CH622KMEB02              C289            
Q_CAP_C0402-22UF,4V,20%,X6S,CHA CH622KMEB02              C290            
Q_CAP_C0402-22UF,4V,20%,X6S,CHA CH622KMEB02              C291            
Q_CAP_C0402-22UF,4V,20%,X6S,CHA CH622KMEB02              C292            
Q_CAP_C0402-22UF,4V,20%,X6S,CHA CH622KMEB02              C293            
Q_CAP_C0402-22UF,4V,20%,X6S,CHA CH622KMEB02              C294            
Q_CAP_C0402-22UF,4V,20%,X6S,CHA CH622KMEB02              C295            
Q_CAP_C0402-22UF,4V,20%,X6S,CHA CH622KMEB02              C296            
Q_CAP_C0402-22UF,4V,20%,X6S,CHA CH622KMEB02              C297            
Q_CAP_C0402-22UF,4V,20%,X6S,CHA CH622KMEB02              C298            
Q_CAP_C0402-22UF,4V,20%,X6S,CHA CH622KMEB02              C299            
Q_CAP_C0402-22UF,4V,20%,X6S,CHA CH622KMEB02              C300            
Q_CAP_C0402-22UF,4V,20%,X6S,CHA CH622KMEB02              C301            
Q_CAP_C0402-22UF,4V,20%,X6S,CHA CH622KMEB02              C302            
Q_CAP_C0402-22UF,4V,20%,X6S,CHA CH622KMEB02              C303            
Q_CAP_C0402-22UF,4V,20%,X6S,CHA CH622KMEB02              C304            
Q_CAP_C0402-22UF,4V,20%,X6S,CHA CH622KMEB02              C305            
Q_CAP_C0402-22UF,4V,20%,X6S,CHA CH622KMEB02              C306            
Q_CAP_C0402-22UF,4V,20%,X6S,CHA CH622KMEB02              C307            
Q_CAP_C0402-22UF,4V,20%,X6S,CHA CH622KMEB02              C308            
Q_CAP_C0402-22UF,4V,20%,X6S,CHA CH622KMEB02              C309            
Q_CAP_C0402-22UF,4V,20%,X6S,CHA CH622KMEB02              C310            
Q_CAP_C0402-22UF,4V,20%,X6S,CHA CH622KMEB02              C399            
Q_CAP_C0402-22UF,4V,20%,X6S,CHA CH622KMEB02              C400            
Q_CAP_C0402-22UF,4V,20%,X6S,CHA CH622KMEB02              C401            
Q_CAP_C0402-22UF,4V,20%,X6S,CHA CH622KMEB02              C402            
Q_CAP_C0402-22UF,4V,20%,X6S,CHA CH622KMEB02              C403            
Q_CAP_C0402-22UF,4V,20%,X6S,CHA CH622KMEB02              C404            
Q_CAP_C0402-22UF,4V,20%,X6S,CHA CH622KMEB02              C405            
Q_CAP_C0402-22UF,4V,20%,X6S,CHA CH622KMEB02              C406            
Q_CAP_C0402-22UF,4V,20%,X6S,CHA CH622KMEB02              C407            
Q_CAP_C0402-22UF,4V,20%,X6S,CHA CH622KMEB02              C408            
Q_CAP_C0402-22UF,4V,20%,X6S,CHA CH622KMEB02              C409            
Q_CAP_C0402-22UF,4V,20%,X6S,CHA CH622KMEB02              C410            
Q_CAP_C0402-22UF,4V,20%,X6S,CHA CH622KMEB02              C411            
Q_CAP_C0402-22UF,4V,20%,X6S,CHA CH622KMEB02              C412            
Q_CAP_C0402-22UF,4V,20%,X6S,CHA CH622KMEB02              C413            
Q_CAP_C0402-22UF,4V,20%,X6S,CHA CH622KMEB02              C414            
Q_CAP_C0402-22UF,4V,20%,X6S,CHA CH622KMEB02              C415            
Q_CAP_C0402-22UF,4V,20%,X6S,CHA CH622KMEB02              C416            
Q_CAP_C0402-22UF,4V,20%,X6S,CHA CH622KMEB02              C417            
Q_CAP_C0402-22UF,4V,20%,X6S,CHA CH622KMEB02              C418            
Q_CAP_C0402-22UF,4V,20%,X6S,CHA CH622KMEB02              C419            
Q_CAP_C0402-22UF,4V,20%,X6S,CHA CH622KMEB02              C420            
Q_CAP_C0402-22UF,4V,20%,X6S,CHA CH622KMEB02              C421            
Q_CAP_C0402-22UF,4V,20%,X6S,CHA CH622KMEB02              C422            
Q_CAP_C0402-22UF,4V,20%,X6S,CHA CH622KMEB02              C423            
Q_CAP_C0402-22UF,4V,20%,X6S,CHA CH622KMEB02              C424            
Q_CAP_C0402-22UF,4V,20%,X6S,CHA CH622KMEB02              C425            
Q_CAP_C0402-22UF,4V,20%,X6S,CHA CH622KMEB02              C426            
Q_CAP_C0402-22UF,4V,20%,X6S,CHA CH622KMEB02              C427            
Q_CAP_C0402-22UF,4V,20%,X6S,CHA CH622KMEB02              C428            
Q_CAP_C0402-22UF,4V,20%,X6S,CHA CH622KMEB02              C429            
Q_CAP_C0402-22UF,4V,20%,X6S,CHA CH622KMEB02              C430            
Q_CAP_C0402-22UF,4V,20%,X6S,CHA CH622KMEB02              C431            
Q_CAP_C0402-22UF,4V,20%,X6S,CHA CH622KMEB02              C432            
Q_CAP_C0402-22UF,4V,20%,X6S,CHA CH622KMEB02              C433            
Q_CAP_C0402-22UF,4V,20%,X6S,CHA CH622KMEB02              C434            
Q_CAP_C0402-22UF,4V,20%,X6S,CHA CH622KMEB02              C435            
Q_CAP_C0402-22UF,4V,20%,X6S,CHA CH622KMEB02              C436            
Q_CAP_C0402-22UF,4V,20%,X6S,CHA CH622KMEB02              C437            
Q_CAP_C0402-22UF,4V,20%,X6S,CHA CH622KMEB02              C438            
Q_CAP_C0402-22UF,4V,20%,X6S,CHA CH622KMEB02              C439            
Q_CAP_C0402-22UF,4V,20%,X6S,CHA CH622KMEB02              C440            
Q_CAP_C0402-22UF,4V,20%,X6S,CHA CH622KMEB02              C441            
Q_CAP_C0402-22UF,4V,20%,X6S,CHA CH622KMEB02              C442            
Q_CAP_C0402-22UF,4V,20%,X6S,CHA CH622KMEB02              C443            
Q_CAP_C0402-22UF,4V,20%,X6S,CHA CH622KMEB02              C444            
Q_CAP_C0402-22UF,4V,20%,X6S,CHA CH622KMEB02              C445            
Q_CAP_C0402-22UF,4V,20%,X6S,CHA CH622KMEB02              C446            
Q_CAP_C0402-22UF,4V,20%,X6S,CHA CH622KMEB02              C490            
Q_CAP_C0402-22UF,4V,20%,X6S,CHA CH622KMEB02              C534            
Q_CAP_C0402-22UF,4V,20%,X6S,CHA CH622KMEB02              C590            
Q_CAP_C0402-22UF,4V,20%,X6S,CHA CH622KMEB02              C966            
Q_CAP_C0402-22UF,4V,20%,X6S,CHA CH622KMEB02              C967            
Q_CAP_C0402-22UF,4V,20%,X6S,CHA CH622KMEB02              C968            
Q_CAP_C0402-22UF,4V,20%,X6S,CHA CH622KMEB02              C969            
Q_CAP_C0402-22UF,4V,20%,X6S,CHA CH622KMEB02              C970            
Q_CAP_C0402-22UF,4V,20%,X6S,CHA CH622KMEB02              C971            
Q_CAP_C0402-22UF,4V,20%,X6S,CHA CH622KMEB02              C972            
Q_CAP_C0402-22UF,4V,20%,X6S,CHA CH622KMEB02              C973            
Q_CAP_C0402-22UF,4V,20%,X6S,CHA CH622KMEB02              C974            
Q_CAP_C0402-22UF,4V,20%,X6S,CHA CH622KMEB02              C975            
Q_CAP_C0402-22UF,4V,20%,X6S,CHA CH622KMEB02              C976            
Q_CAP_C0402-22UF,4V,20%,X6S,CHA CH622KMEB02              C977            
Q_CAP_C0402-22UF,4V,20%,X6S,CHA CH622KMEB02              C978            
Q_CAP_C0402-22UF,4V,20%,X6S,CHA CH622KMEB02              C979            
Q_CAP_C0402-22UF,4V,20%,X6S,CHA CH622KMEB02              C980            
Q_CAP_C0402-22UF,4V,20%,X6S,CHA CH622KMEB02              C981            
Q_CAP_C0402-22UF,4V,20%,X6S,CHA CH622KMEB02              C982            
Q_CAP_C0402-22UF,4V,20%,X6S,CHA CH622KMEB02              C983            
Q_CAP_C0402-22UF,4V,20%,X6S,CHA CH622KMEB02              C984            
Q_CAP_C0402-22UF,4V,20%,X6S,CHA CH622KMEB02              C985            
Q_CAP_C0402-22UF,4V,20%,X6S,CHA CH622KMEB02              C986            
Q_CAP_C0402-22UF,4V,20%,X6S,CHA CH622KMEB02              C987            
Q_CAP_C0402-22UF,4V,20%,X6S,CHA CH622KMEB02              C988            
Q_CAP_C0402-22UF,4V,20%,X6S,CHA CH622KMEB02              C989            
Q_CAP_C0402-22UF,4V,20%,X6S,CHA CH622KMEB02              C990            
Q_CAP_C0402-22UF,4V,20%,X6S,CHA CH622KMEB02              C991            
Q_CAP_C0402-22UF,4V,20%,X6S,CHA CH622KMEB02              C992            
Q_CAP_C0402-22UF,4V,20%,X6S,CHA CH622KMEB02              C993            
Q_CAP_C0402-22UF,4V,20%,X6S,CHA CH622KMEB02              C994            
Q_CAP_C0402-22UF,4V,20%,X6S,CHA CH622KMEB02              C995            
Q_CAP_C0402-22UF,4V,20%,X6S,CHA CH622KMEB02              C996            
Q_CAP_C0402-22UF,4V,20%,X6S,CHA CH622KMEB02              C997            
Q_CAP_C0402-22UF,4V,20%,X6S,CHA CH622KMEB02              C998            
Q_CAP_C0402-22UF,4V,20%,X6S,CHA CH622KMEB02              C999            
Q_CAP_C0402-22UF,4V,20%,X6S,CHA CH622KMEB02              C1000           
Q_CAP_C0402-22UF,4V,20%,X6S,CHA CH622KMEB02              C1001           
Q_CAP_C0402-22UF,4V,20%,X6S,CHA CH622KMEB02              C1002           
Q_CAP_C0402-22UF,4V,20%,X6S,CHA CH622KMEB02              C1003           
Q_CAP_C0402-22UF,4V,20%,X6S,CHA CH622KMEB02              C1004           
Q_CAP_C0402-22UF,4V,20%,X6S,CHA CH622KMEB02              C1005           
Q_CAP_C0402-22UF,4V,20%,X6S,CHA CH622KMEB02              C1006           
Q_CAP_C0402-22UF,4V,20%,X6S,CHA CH622KMEB02              C1007           
Q_CAP_C0402-22UF,4V,20%,X6S,CHA CH622KMEB02              C1008           
Q_CAP_C0402-22UF,4V,20%,X6S,CHA CH622KMEB02              C1009           
Q_CAP_C0402-22UF,4V,20%,X6S,CHA CH622KMEB02              C1010           
Q_CAP_C0402-22UF,4V,20%,X6S,CHA CH622KMEB02              C1011           
Q_CAP_C0402-22UF,4V,20%,X6S,CHA CH622KMEB02              C1012           
Q_CAP_C0402-22UF,4V,20%,X6S,CHA CH622KMEB02              C1013           
Q_CAP_C0402-22UF,4V,20%,X6S,CHA CH622KMEB02              C1014           
Q_CAP_C0402-22UF,4V,20%,X6S,CHA CH622KMEB02              C1015           
Q_CAP_C0402-22UF,4V,20%,X6S,CHA CH622KMEB02              C1016           
Q_CAP_C0402-22UF,4V,20%,X6S,CHA CH622KMEB02              C1017           
Q_CAP_C0402-22UF,4V,20%,X6S,CHA CH622KMEB02              C1018           
Q_CAP_C0402-22UF,4V,20%,X6S,CHA CH622KMEB02              C1019           
Q_CAP_C0402-22UF,4V,20%,X6S,CHA CH622KMEB02              C1020           
Q_CAP_C0402-22UF,4V,20%,X6S,CHA CH622KMEB02              C1021           
Q_CAP_C0402-22UF,4V,20%,X6S,CHA CH622KMEB02              C1022           
Q_CAP_C0402-22UF,4V,20%,X6S,CHA CH622KMEB02              C1023           
Q_CAP_C0402-22UF,4V,20%,X6S,CHA CH622KMEB02              C1024           
Q_CAP_C0402-22UF,4V,20%,X6S,CHA CH622KMEB02              C1025           
Q_CAP_C0402-22UF,4V,20%,X6S,CHA CH622KMEB02              C1026           
Q_CAP_C0402-22UF,4V,20%,X6S,CHA CH622KMEB02              C1027           
Q_CAP_C0402-22UF,4V,20%,X6S,CHA CH622KMEB02              C1028           
Q_CAP_C0402-22UF,4V,20%,X6S,CHA CH622KMEB02              C1029           
Q_CAP_C0402-22UF,4V,20%,X6S,CHA CH622KMEB02              C1030           
Q_CAP_C0402-22UF,4V,20%,X6S,CHA CH622KMEB02              C1031           
Q_CAP_C0402-22UF,4V,20%,X6S,CHA CH622KMEB02              C1032           
Q_CAP_C0402-22UF,4V,20%,X6S,CHA CH622KMEB02              C1033           
Q_CAP_C0402-22UF,4V,20%,X6S,CHA CH622KMEB02              C1034           
Q_CAP_C0402-22UF,4V,20%,X6S,CHA CH622KMEB02              C1035           
Q_CAP_C0402-22UF,4V,20%,X6S,CHA CH622KMEB02              C1036           
Q_CAP_C0402-22UF,4V,20%,X6S,CHA CH622KMEB02              C1037           
Q_CAP_C0402-22UF,4V,20%,X6S,CHA CH622KMEB02              C1038           
Q_CAP_C0402-22UF,4V,20%,X6S,CHA CH622KMEB02              C1039           
Q_CAP_C0402-22UF,4V,20%,X6S,CHA CH622KMEB02              C1040           
Q_CAP_C0402-22UF,4V,20%,X6S,CHA CH622KMEB02              C1041           
Q_CAP_C0402-22UF,4V,20%,X6S,CHA CH622KMEB02              C1043           
Q_CAP_C0402-22UF,4V,20%,X6S,CHA CH622KMEB02              C1044           
Q_CAP_C0402-22UF,4V,20%,X6S,CHA CH622KMEB02              C1045           
Q_CAP_C0402-22UF,4V,20%,X6S,CHA CH622KMEB02              C1302           
Q_CAP_C0402-22UF,4V,20%,X6S,CHA CH622KMEB02              C1353           
Q_CAP_C0402-22UF,4V,20%,X6S,CHA CH622KMEB02              C1362           
Q_CAP_C0402-22UF,4V,20%,X6S,CHA CH622KMEB02              C1363           
Q_CAP_C0402-22UF,4V,20%,X6S,CHA CH622KMEB02              C1364           
Q_CAP_C0402-22UF,4V,20%,X6S,CHA CH622KMEB02              C1365           
Q_CAP_C0402-22UF,4V,20%,X6S,CHA CH622KMEB02              C1366           

----------------

Q_CAP_C0402-3900PF,50V,10%,X7RA CH23906KB14              C588            

----------------

Q_CAP_C0402-470PF,50V,5%,NPO,CA CH1476J0B08              PC1223          

----------------

Q_CAP_C0603-10UF,4V,20%,EMPTY,A CH610KME907              PC327           
Q_CAP_C0603-10UF,4V,20%,EMPTY,A CH610KME907              PC545           

----------------

Q_CAP_C0603-10UF,6.3V,20%,X6S,A CH6101ME900              C108            
Q_CAP_C0603-10UF,6.3V,20%,X6S,A CH6101ME900              C172            
Q_CAP_C0603-10UF,6.3V,20%,X6S,A CH6101ME900              C208            
Q_CAP_C0603-10UF,6.3V,20%,X6S,A CH6101ME900              C209            
Q_CAP_C0603-10UF,6.3V,20%,X6S,A CH6101ME900              C1251           
Q_CAP_C0603-10UF,6.3V,20%,X6S,A CH6101ME900              C1252           
Q_CAP_C0603-10UF,6.3V,20%,X6S,A CH6101ME900              C1254           
Q_CAP_C0603-10UF,6.3V,20%,X6S,A CH6101ME900              C1255           
Q_CAP_C0603-10UF,6.3V,20%,X6S,A CH6101ME900              C1260           
Q_CAP_C0603-10UF,6.3V,20%,X6S,A CH6101ME900              C1261           
Q_CAP_C0603-10UF,6.3V,20%,X6S,A CH6101ME900              C1309           
Q_CAP_C0603-10UF,6.3V,20%,X6S,A CH6101ME900              C1310           
Q_CAP_C0603-10UF,6.3V,20%,X6S,A CH6101ME900              C1313           
Q_CAP_C0603-10UF,6.3V,20%,X6S,A CH6101ME900              C1314           
Q_CAP_C0603-10UF,6.3V,20%,X6S,A CH6101ME900              C1409           

----------------

Q_CAP_C0603-2.2UF,16V,10%,X6S,A CH5223KE901              PC591           

----------------

Q_CAP_C0603-22UF,4V,20%,X6S,CHA CH622KME901              C1178           
Q_CAP_C0603-22UF,4V,20%,X6S,CHA CH622KME901              C1181           
Q_CAP_C0603-22UF,4V,20%,X6S,CHA CH622KME901              C1182           
Q_CAP_C0603-22UF,4V,20%,X6S,CHA CH622KME901              C1184           
Q_CAP_C0603-22UF,4V,20%,X6S,CHA CH622KME901              C1185           
Q_CAP_C0603-22UF,4V,20%,X6S,CHA CH622KME901              C1186           
Q_CAP_C0603-22UF,4V,20%,X6S,CHA CH622KME901              C1187           
Q_CAP_C0603-22UF,4V,20%,X6S,CHA CH622KME901              C1191           
Q_CAP_C0603-22UF,4V,20%,X6S,CHA CH622KME901              C1192           
Q_CAP_C0603-22UF,4V,20%,X6S,CHA CH622KME901              C1197           
Q_CAP_C0603-22UF,4V,20%,X6S,CHA CH622KME901              C1198           
Q_CAP_C0603-22UF,4V,20%,X6S,CHA CH622KME901              C1201           
Q_CAP_C0603-22UF,4V,20%,X6S,CHA CH622KME901              C1202           

----------------

Q_CAP_C0603-22UF,6.3V,20%,X6S,A CH6221ME900              C1078           
Q_CAP_C0603-22UF,6.3V,20%,X6S,A CH6221ME900              C1080           
Q_CAP_C0603-22UF,6.3V,20%,X6S,A CH6221ME900              C1082           
Q_CAP_C0603-22UF,6.3V,20%,X6S,A CH6221ME900              C1337           
Q_CAP_C0603-22UF,6.3V,20%,X6S,A CH6221ME900              C1341           
Q_CAP_C0603-22UF,6.3V,20%,X6S,A CH6221ME900              C1342           
Q_CAP_C0603-22UF,6.3V,20%,X6S,A CH6221ME900              C1343           

----------------

Q_CAP_C0603-4.7UF,16V,10%,X6S,A CH5473KE902              PC581           

----------------

Q_CAP_C0603-47UF,2.5V,20%,X6S,A CH647LME901              C337            
Q_CAP_C0603-47UF,2.5V,20%,X6S,A CH647LME901              C340            
Q_CAP_C0603-47UF,2.5V,20%,X6S,A CH647LME901              C381            
Q_CAP_C0603-47UF,2.5V,20%,X6S,A CH647LME901              C384            
Q_CAP_C0603-47UF,2.5V,20%,X6S,A CH647LME901              C465            
Q_CAP_C0603-47UF,2.5V,20%,X6S,A CH647LME901              C471            
Q_CAP_C0603-47UF,2.5V,20%,X6S,A CH647LME901              C472            
Q_CAP_C0603-47UF,2.5V,20%,X6S,A CH647LME901              C474            
Q_CAP_C0603-47UF,2.5V,20%,X6S,A CH647LME901              C475            
Q_CAP_C0603-47UF,2.5V,20%,X6S,A CH647LME901              C480            
Q_CAP_C0603-47UF,2.5V,20%,X6S,A CH647LME901              C483            
Q_CAP_C0603-47UF,2.5V,20%,X6S,A CH647LME901              C488            
Q_CAP_C0603-47UF,2.5V,20%,X6S,A CH647LME901              C489            
Q_CAP_C0603-47UF,2.5V,20%,X6S,A CH647LME901              C509            
Q_CAP_C0603-47UF,2.5V,20%,X6S,A CH647LME901              C515            
Q_CAP_C0603-47UF,2.5V,20%,X6S,A CH647LME901              C516            
Q_CAP_C0603-47UF,2.5V,20%,X6S,A CH647LME901              C518            
Q_CAP_C0603-47UF,2.5V,20%,X6S,A CH647LME901              C519            
Q_CAP_C0603-47UF,2.5V,20%,X6S,A CH647LME901              C524            
Q_CAP_C0603-47UF,2.5V,20%,X6S,A CH647LME901              C527            
Q_CAP_C0603-47UF,2.5V,20%,X6S,A CH647LME901              C532            
Q_CAP_C0603-47UF,2.5V,20%,X6S,A CH647LME901              C533            
Q_CAP_C0603-47UF,2.5V,20%,X6S,A CH647LME901              C1389           
Q_CAP_C0603-47UF,2.5V,20%,X6S,A CH647LME901              C1391           
Q_CAP_C0603-47UF,2.5V,20%,X6S,A CH647LME901              C1393           
Q_CAP_C0603-47UF,2.5V,20%,X6S,A CH647LME901              C1405           
Q_CAP_C0603-47UF,2.5V,20%,X6S,A CH647LME901              C1406           
Q_CAP_C0603-47UF,2.5V,20%,X6S,A CH647LME901              C1407           

----------------

Q_CAP_C0805-100UF,4V,20%,X6S,CA CH710KMEA00              C311            
Q_CAP_C0805-100UF,4V,20%,X6S,CA CH710KMEA00              C312            
Q_CAP_C0805-100UF,4V,20%,X6S,CA CH710KMEA00              C313            
Q_CAP_C0805-100UF,4V,20%,X6S,CA CH710KMEA00              C314            
Q_CAP_C0805-100UF,4V,20%,X6S,CA CH710KMEA00              C315            
Q_CAP_C0805-100UF,4V,20%,X6S,CA CH710KMEA00              C316            
Q_CAP_C0805-100UF,4V,20%,X6S,CA CH710KMEA00              C317            
Q_CAP_C0805-100UF,4V,20%,X6S,CA CH710KMEA00              C318            
Q_CAP_C0805-100UF,4V,20%,X6S,CA CH710KMEA00              C320            
Q_CAP_C0805-100UF,4V,20%,X6S,CA CH710KMEA00              C321            
Q_CAP_C0805-100UF,4V,20%,X6S,CA CH710KMEA00              C322            
Q_CAP_C0805-100UF,4V,20%,X6S,CA CH710KMEA00              C323            
Q_CAP_C0805-100UF,4V,20%,X6S,CA CH710KMEA00              C324            
Q_CAP_C0805-100UF,4V,20%,X6S,CA CH710KMEA00              C325            
Q_CAP_C0805-100UF,4V,20%,X6S,CA CH710KMEA00              C326            
Q_CAP_C0805-100UF,4V,20%,X6S,CA CH710KMEA00              C327            
Q_CAP_C0805-100UF,4V,20%,X6S,CA CH710KMEA00              C328            
Q_CAP_C0805-100UF,4V,20%,X6S,CA CH710KMEA00              C329            
Q_CAP_C0805-100UF,4V,20%,X6S,CA CH710KMEA00              C330            
Q_CAP_C0805-100UF,4V,20%,X6S,CA CH710KMEA00              C332            
Q_CAP_C0805-100UF,4V,20%,X6S,CA CH710KMEA00              C333            
Q_CAP_C0805-100UF,4V,20%,X6S,CA CH710KMEA00              C335            
Q_CAP_C0805-100UF,4V,20%,X6S,CA CH710KMEA00              C336            
Q_CAP_C0805-100UF,4V,20%,X6S,CA CH710KMEA00              C338            
Q_CAP_C0805-100UF,4V,20%,X6S,CA CH710KMEA00              C339            
Q_CAP_C0805-100UF,4V,20%,X6S,CA CH710KMEA00              C341            
Q_CAP_C0805-100UF,4V,20%,X6S,CA CH710KMEA00              C342            
Q_CAP_C0805-100UF,4V,20%,X6S,CA CH710KMEA00              C343            
Q_CAP_C0805-100UF,4V,20%,X6S,CA CH710KMEA00              C344            
Q_CAP_C0805-100UF,4V,20%,X6S,CA CH710KMEA00              C345            
Q_CAP_C0805-100UF,4V,20%,X6S,CA CH710KMEA00              C346            
Q_CAP_C0805-100UF,4V,20%,X6S,CA CH710KMEA00              C347            
Q_CAP_C0805-100UF,4V,20%,X6S,CA CH710KMEA00              C348            
Q_CAP_C0805-100UF,4V,20%,X6S,CA CH710KMEA00              C349            
Q_CAP_C0805-100UF,4V,20%,X6S,CA CH710KMEA00              C350            
Q_CAP_C0805-100UF,4V,20%,X6S,CA CH710KMEA00              C351            
Q_CAP_C0805-100UF,4V,20%,X6S,CA CH710KMEA00              C352            
Q_CAP_C0805-100UF,4V,20%,X6S,CA CH710KMEA00              C353            
Q_CAP_C0805-100UF,4V,20%,X6S,CA CH710KMEA00              C354            
Q_CAP_C0805-100UF,4V,20%,X6S,CA CH710KMEA00              C355            
Q_CAP_C0805-100UF,4V,20%,X6S,CA CH710KMEA00              C356            
Q_CAP_C0805-100UF,4V,20%,X6S,CA CH710KMEA00              C357            
Q_CAP_C0805-100UF,4V,20%,X6S,CA CH710KMEA00              C358            
Q_CAP_C0805-100UF,4V,20%,X6S,CA CH710KMEA00              C359            
Q_CAP_C0805-100UF,4V,20%,X6S,CA CH710KMEA00              C360            
Q_CAP_C0805-100UF,4V,20%,X6S,CA CH710KMEA00              C361            
Q_CAP_C0805-100UF,4V,20%,X6S,CA CH710KMEA00              C362            
Q_CAP_C0805-100UF,4V,20%,X6S,CA CH710KMEA00              C363            
Q_CAP_C0805-100UF,4V,20%,X6S,CA CH710KMEA00              C364            
Q_CAP_C0805-100UF,4V,20%,X6S,CA CH710KMEA00              C365            
Q_CAP_C0805-100UF,4V,20%,X6S,CA CH710KMEA00              C366            
Q_CAP_C0805-100UF,4V,20%,X6S,CA CH710KMEA00              C367            
Q_CAP_C0805-100UF,4V,20%,X6S,CA CH710KMEA00              C368            
Q_CAP_C0805-100UF,4V,20%,X6S,CA CH710KMEA00              C369            
Q_CAP_C0805-100UF,4V,20%,X6S,CA CH710KMEA00              C370            
Q_CAP_C0805-100UF,4V,20%,X6S,CA CH710KMEA00              C371            
Q_CAP_C0805-100UF,4V,20%,X6S,CA CH710KMEA00              C372            
Q_CAP_C0805-100UF,4V,20%,X6S,CA CH710KMEA00              C373            
Q_CAP_C0805-100UF,4V,20%,X6S,CA CH710KMEA00              C374            
Q_CAP_C0805-100UF,4V,20%,X6S,CA CH710KMEA00              C376            
Q_CAP_C0805-100UF,4V,20%,X6S,CA CH710KMEA00              C377            
Q_CAP_C0805-100UF,4V,20%,X6S,CA CH710KMEA00              C379            
Q_CAP_C0805-100UF,4V,20%,X6S,CA CH710KMEA00              C380            
Q_CAP_C0805-100UF,4V,20%,X6S,CA CH710KMEA00              C382            
Q_CAP_C0805-100UF,4V,20%,X6S,CA CH710KMEA00              C383            
Q_CAP_C0805-100UF,4V,20%,X6S,CA CH710KMEA00              C385            
Q_CAP_C0805-100UF,4V,20%,X6S,CA CH710KMEA00              C386            
Q_CAP_C0805-100UF,4V,20%,X6S,CA CH710KMEA00              C387            
Q_CAP_C0805-100UF,4V,20%,X6S,CA CH710KMEA00              C388            
Q_CAP_C0805-100UF,4V,20%,X6S,CA CH710KMEA00              C389            
Q_CAP_C0805-100UF,4V,20%,X6S,CA CH710KMEA00              C390            
Q_CAP_C0805-100UF,4V,20%,X6S,CA CH710KMEA00              C391            
Q_CAP_C0805-100UF,4V,20%,X6S,CA CH710KMEA00              C392            
Q_CAP_C0805-100UF,4V,20%,X6S,CA CH710KMEA00              C393            
Q_CAP_C0805-100UF,4V,20%,X6S,CA CH710KMEA00              C394            
Q_CAP_C0805-100UF,4V,20%,X6S,CA CH710KMEA00              C395            
Q_CAP_C0805-100UF,4V,20%,X6S,CA CH710KMEA00              C396            
Q_CAP_C0805-100UF,4V,20%,X6S,CA CH710KMEA00              C397            
Q_CAP_C0805-100UF,4V,20%,X6S,CA CH710KMEA00              C398            
Q_CAP_C0805-100UF,4V,20%,X6S,CA CH710KMEA00              C447            
Q_CAP_C0805-100UF,4V,20%,X6S,CA CH710KMEA00              C448            
Q_CAP_C0805-100UF,4V,20%,X6S,CA CH710KMEA00              C449            
Q_CAP_C0805-100UF,4V,20%,X6S,CA CH710KMEA00              C450            
Q_CAP_C0805-100UF,4V,20%,X6S,CA CH710KMEA00              C451            
Q_CAP_C0805-100UF,4V,20%,X6S,CA CH710KMEA00              C452            
Q_CAP_C0805-100UF,4V,20%,X6S,CA CH710KMEA00              C453            
Q_CAP_C0805-100UF,4V,20%,X6S,CA CH710KMEA00              C454            
Q_CAP_C0805-100UF,4V,20%,X6S,CA CH710KMEA00              C455            
Q_CAP_C0805-100UF,4V,20%,X6S,CA CH710KMEA00              C456            
Q_CAP_C0805-100UF,4V,20%,X6S,CA CH710KMEA00              C457            
Q_CAP_C0805-100UF,4V,20%,X6S,CA CH710KMEA00              C458            
Q_CAP_C0805-100UF,4V,20%,X6S,CA CH710KMEA00              C459            
Q_CAP_C0805-100UF,4V,20%,X6S,CA CH710KMEA00              C460            
Q_CAP_C0805-100UF,4V,20%,X6S,CA CH710KMEA00              C461            
Q_CAP_C0805-100UF,4V,20%,X6S,CA CH710KMEA00              C462            
Q_CAP_C0805-100UF,4V,20%,X6S,CA CH710KMEA00              C463            
Q_CAP_C0805-100UF,4V,20%,X6S,CA CH710KMEA00              C464            
Q_CAP_C0805-100UF,4V,20%,X6S,CA CH710KMEA00              C466            
Q_CAP_C0805-100UF,4V,20%,X6S,CA CH710KMEA00              C467            
Q_CAP_C0805-100UF,4V,20%,X6S,CA CH710KMEA00              C468            
Q_CAP_C0805-100UF,4V,20%,X6S,CA CH710KMEA00              C470            
Q_CAP_C0805-100UF,4V,20%,X6S,CA CH710KMEA00              C473            
Q_CAP_C0805-100UF,4V,20%,X6S,CA CH710KMEA00              C476            
Q_CAP_C0805-100UF,4V,20%,X6S,CA CH710KMEA00              C477            
Q_CAP_C0805-100UF,4V,20%,X6S,CA CH710KMEA00              C478            
Q_CAP_C0805-100UF,4V,20%,X6S,CA CH710KMEA00              C479            
Q_CAP_C0805-100UF,4V,20%,X6S,CA CH710KMEA00              C481            
Q_CAP_C0805-100UF,4V,20%,X6S,CA CH710KMEA00              C482            
Q_CAP_C0805-100UF,4V,20%,X6S,CA CH710KMEA00              C484            
Q_CAP_C0805-100UF,4V,20%,X6S,CA CH710KMEA00              C485            
Q_CAP_C0805-100UF,4V,20%,X6S,CA CH710KMEA00              C486            
Q_CAP_C0805-100UF,4V,20%,X6S,CA CH710KMEA00              C487            
Q_CAP_C0805-100UF,4V,20%,X6S,CA CH710KMEA00              C491            
Q_CAP_C0805-100UF,4V,20%,X6S,CA CH710KMEA00              C492            
Q_CAP_C0805-100UF,4V,20%,X6S,CA CH710KMEA00              C493            
Q_CAP_C0805-100UF,4V,20%,X6S,CA CH710KMEA00              C494            
Q_CAP_C0805-100UF,4V,20%,X6S,CA CH710KMEA00              C495            
Q_CAP_C0805-100UF,4V,20%,X6S,CA CH710KMEA00              C496            
Q_CAP_C0805-100UF,4V,20%,X6S,CA CH710KMEA00              C497            
Q_CAP_C0805-100UF,4V,20%,X6S,CA CH710KMEA00              C498            
Q_CAP_C0805-100UF,4V,20%,X6S,CA CH710KMEA00              C499            
Q_CAP_C0805-100UF,4V,20%,X6S,CA CH710KMEA00              C500            
Q_CAP_C0805-100UF,4V,20%,X6S,CA CH710KMEA00              C501            
Q_CAP_C0805-100UF,4V,20%,X6S,CA CH710KMEA00              C502            
Q_CAP_C0805-100UF,4V,20%,X6S,CA CH710KMEA00              C503            
Q_CAP_C0805-100UF,4V,20%,X6S,CA CH710KMEA00              C504            
Q_CAP_C0805-100UF,4V,20%,X6S,CA CH710KMEA00              C505            
Q_CAP_C0805-100UF,4V,20%,X6S,CA CH710KMEA00              C506            
Q_CAP_C0805-100UF,4V,20%,X6S,CA CH710KMEA00              C507            
Q_CAP_C0805-100UF,4V,20%,X6S,CA CH710KMEA00              C508            
Q_CAP_C0805-100UF,4V,20%,X6S,CA CH710KMEA00              C510            
Q_CAP_C0805-100UF,4V,20%,X6S,CA CH710KMEA00              C511            
Q_CAP_C0805-100UF,4V,20%,X6S,CA CH710KMEA00              C512            
Q_CAP_C0805-100UF,4V,20%,X6S,CA CH710KMEA00              C514            
Q_CAP_C0805-100UF,4V,20%,X6S,CA CH710KMEA00              C517            
Q_CAP_C0805-100UF,4V,20%,X6S,CA CH710KMEA00              C520            
Q_CAP_C0805-100UF,4V,20%,X6S,CA CH710KMEA00              C521            
Q_CAP_C0805-100UF,4V,20%,X6S,CA CH710KMEA00              C522            
Q_CAP_C0805-100UF,4V,20%,X6S,CA CH710KMEA00              C523            
Q_CAP_C0805-100UF,4V,20%,X6S,CA CH710KMEA00              C525            
Q_CAP_C0805-100UF,4V,20%,X6S,CA CH710KMEA00              C526            
Q_CAP_C0805-100UF,4V,20%,X6S,CA CH710KMEA00              C528            
Q_CAP_C0805-100UF,4V,20%,X6S,CA CH710KMEA00              C529            
Q_CAP_C0805-100UF,4V,20%,X6S,CA CH710KMEA00              C530            
Q_CAP_C0805-100UF,4V,20%,X6S,CA CH710KMEA00              C531            
Q_CAP_C0805-100UF,4V,20%,X6S,CA CH710KMEA00              C1387           
Q_CAP_C0805-100UF,4V,20%,X6S,CA CH710KMEA00              C1388           
Q_CAP_C0805-100UF,4V,20%,X6S,CA CH710KMEA00              C1390           
Q_CAP_C0805-100UF,4V,20%,X6S,CA CH710KMEA00              C1392           
Q_CAP_C0805-100UF,4V,20%,X6S,CA CH710KMEA00              C1396           
Q_CAP_C0805-100UF,4V,20%,X6S,CA CH710KMEA00              C1397           
Q_CAP_C0805-100UF,4V,20%,X6S,CA CH710KMEA00              C1398           
Q_CAP_C0805-100UF,4V,20%,X6S,CA CH710KMEA00              C1399           
Q_CAP_C0805-100UF,4V,20%,X6S,CA CH710KMEA00              C1400           
Q_CAP_C0805-100UF,4V,20%,X6S,CA CH710KMEA00              C1403           
Q_CAP_C0805-100UF,4V,20%,X6S,CA CH710KMEA00              C1404           

----------------

Q_CAP_C0805-10UF,16V,10%,EMPTYA CH6103KEA00              C1171           
Q_CAP_C0805-10UF,16V,10%,EMPTYA CH6103KEA00              C1338           

----------------

Q_CAP_C0805-10UF,16V,10%,X6S,CA CH6103KEA00              C1170           
Q_CAP_C0805-10UF,16V,10%,X6S,CA CH6103KEA00              C1331           
Q_CAP_C0805-10UF,16V,10%,X6S,CA CH6103KEA00              C1333           
Q_CAP_C0805-10UF,16V,10%,X6S,CA CH6103KEA00              C1340           
Q_CAP_C0805-10UF,16V,10%,X6S,CA CH6103KEA00              PC1232          
Q_CAP_C0805-10UF,16V,10%,X6S,CA CH6103KEA00              PC1233          

----------------

Q_CAP_C0805-10UF,16V,10%,X7R,CA CH6103K1A00              C3              
Q_CAP_C0805-10UF,16V,10%,X7R,CA CH6103K1A00              C4              
Q_CAP_C0805-10UF,16V,10%,X7R,CA CH6103K1A00              C6              
Q_CAP_C0805-10UF,16V,10%,X7R,CA CH6103K1A00              C7              
Q_CAP_C0805-10UF,16V,10%,X7R,CA CH6103K1A00              C9              
Q_CAP_C0805-10UF,16V,10%,X7R,CA CH6103K1A00              C10             
Q_CAP_C0805-10UF,16V,10%,X7R,CA CH6103K1A00              C12             
Q_CAP_C0805-10UF,16V,10%,X7R,CA CH6103K1A00              C13             
Q_CAP_C0805-10UF,16V,10%,X7R,CA CH6103K1A00              C15             
Q_CAP_C0805-10UF,16V,10%,X7R,CA CH6103K1A00              C16             
Q_CAP_C0805-10UF,16V,10%,X7R,CA CH6103K1A00              C18             
Q_CAP_C0805-10UF,16V,10%,X7R,CA CH6103K1A00              C19             
Q_CAP_C0805-10UF,16V,10%,X7R,CA CH6103K1A00              C21             
Q_CAP_C0805-10UF,16V,10%,X7R,CA CH6103K1A00              C22             
Q_CAP_C0805-10UF,16V,10%,X7R,CA CH6103K1A00              C24             
Q_CAP_C0805-10UF,16V,10%,X7R,CA CH6103K1A00              C27             
Q_CAP_C0805-10UF,16V,10%,X7R,CA CH6103K1A00              C28             
Q_CAP_C0805-10UF,16V,10%,X7R,CA CH6103K1A00              C30             
Q_CAP_C0805-10UF,16V,10%,X7R,CA CH6103K1A00              C31             
Q_CAP_C0805-10UF,16V,10%,X7R,CA CH6103K1A00              C33             
Q_CAP_C0805-10UF,16V,10%,X7R,CA CH6103K1A00              C34             
Q_CAP_C0805-10UF,16V,10%,X7R,CA CH6103K1A00              C36             
Q_CAP_C0805-10UF,16V,10%,X7R,CA CH6103K1A00              C37             
Q_CAP_C0805-10UF,16V,10%,X7R,CA CH6103K1A00              C39             
Q_CAP_C0805-10UF,16V,10%,X7R,CA CH6103K1A00              C40             
Q_CAP_C0805-10UF,16V,10%,X7R,CA CH6103K1A00              C42             
Q_CAP_C0805-10UF,16V,10%,X7R,CA CH6103K1A00              C43             
Q_CAP_C0805-10UF,16V,10%,X7R,CA CH6103K1A00              C45             
Q_CAP_C0805-10UF,16V,10%,X7R,CA CH6103K1A00              C46             
Q_CAP_C0805-10UF,16V,10%,X7R,CA CH6103K1A00              C48             
Q_CAP_C0805-10UF,16V,10%,X7R,CA CH6103K1A00              C49             
Q_CAP_C0805-10UF,16V,10%,X7R,CA CH6103K1A00              C51             
Q_CAP_C0805-10UF,16V,10%,X7R,CA CH6103K1A00              C52             
Q_CAP_C0805-10UF,16V,10%,X7R,CA CH6103K1A00              C54             
Q_CAP_C0805-10UF,16V,10%,X7R,CA CH6103K1A00              C55             
Q_CAP_C0805-10UF,16V,10%,X7R,CA CH6103K1A00              C57             
Q_CAP_C0805-10UF,16V,10%,X7R,CA CH6103K1A00              C58             
Q_CAP_C0805-10UF,16V,10%,X7R,CA CH6103K1A00              C60             
Q_CAP_C0805-10UF,16V,10%,X7R,CA CH6103K1A00              C61             
Q_CAP_C0805-10UF,16V,10%,X7R,CA CH6103K1A00              C63             
Q_CAP_C0805-10UF,16V,10%,X7R,CA CH6103K1A00              C64             
Q_CAP_C0805-10UF,16V,10%,X7R,CA CH6103K1A00              C66             
Q_CAP_C0805-10UF,16V,10%,X7R,CA CH6103K1A00              C67             
Q_CAP_C0805-10UF,16V,10%,X7R,CA CH6103K1A00              C69             
Q_CAP_C0805-10UF,16V,10%,X7R,CA CH6103K1A00              C70             
Q_CAP_C0805-10UF,16V,10%,X7R,CA CH6103K1A00              C73             
Q_CAP_C0805-10UF,16V,10%,X7R,CA CH6103K1A00              C74             
Q_CAP_C0805-10UF,16V,10%,X7R,CA CH6103K1A00              C76             
Q_CAP_C0805-10UF,16V,10%,X7R,CA CH6103K1A00              C77             
Q_CAP_C0805-10UF,16V,10%,X7R,CA CH6103K1A00              C79             
Q_CAP_C0805-10UF,16V,10%,X7R,CA CH6103K1A00              C80             
Q_CAP_C0805-10UF,16V,10%,X7R,CA CH6103K1A00              C82             
Q_CAP_C0805-10UF,16V,10%,X7R,CA CH6103K1A00              C83             
Q_CAP_C0805-10UF,16V,10%,X7R,CA CH6103K1A00              C85             
Q_CAP_C0805-10UF,16V,10%,X7R,CA CH6103K1A00              C86             
Q_CAP_C0805-10UF,16V,10%,X7R,CA CH6103K1A00              C88             
Q_CAP_C0805-10UF,16V,10%,X7R,CA CH6103K1A00              C89             
Q_CAP_C0805-10UF,16V,10%,X7R,CA CH6103K1A00              C91             
Q_CAP_C0805-10UF,16V,10%,X7R,CA CH6103K1A00              C92             
Q_CAP_C0805-10UF,16V,10%,X7R,CA CH6103K1A00              C94             
Q_CAP_C0805-10UF,16V,10%,X7R,CA CH6103K1A00              C95             
Q_CAP_C0805-10UF,16V,10%,X7R,CA CH6103K1A00              C97             
Q_CAP_C0805-10UF,16V,10%,X7R,CA CH6103K1A00              C98             

----------------

Q_CAP_C0805-10UF,25V,10%,X6S,CA CH6104KEA00              C184            
Q_CAP_C0805-10UF,25V,10%,X6S,CA CH6104KEA00              C563            
Q_CAP_C0805-10UF,25V,10%,X6S,CA CH6104KEA00              C587            
Q_CAP_C0805-10UF,25V,10%,X6S,CA CH6104KEA00              C632            
Q_CAP_C0805-10UF,25V,10%,X6S,CA CH6104KEA00              C1359           
Q_CAP_C0805-10UF,25V,10%,X6S,CA CH6104KEA00              C1361           
Q_CAP_C0805-10UF,25V,10%,X6S,CA CH6104KEA00              C1431           
Q_CAP_C0805-10UF,25V,10%,X6S,CA CH6104KEA00              C1433           
Q_CAP_C0805-10UF,25V,10%,X6S,CA CH6104KEA00              C1483           
Q_CAP_C0805-10UF,25V,10%,X6S,CA CH6104KEA00              C1487           
Q_CAP_C0805-10UF,25V,10%,X6S,CA CH6104KEA00              C1488           
Q_CAP_C0805-10UF,25V,10%,X6S,CA CH6104KEA00              C1506           
Q_CAP_C0805-10UF,25V,10%,X6S,CA CH6104KEA00              C1509           
Q_CAP_C0805-10UF,25V,10%,X6S,CA CH6104KEA00              C1514           
Q_CAP_C0805-10UF,25V,10%,X6S,CA CH6104KEA00              C1515           
Q_CAP_C0805-10UF,25V,10%,X6S,CA CH6104KEA00              C1598           

----------------

Q_CAP_C0805-22UF,10V,20%,X6S,CA CH6222MEA00              C1599           
Q_CAP_C0805-22UF,10V,20%,X6S,CA CH6222MEA00              C1600           
Q_CAP_C0805-22UF,10V,20%,X6S,CA CH6222MEA00              PC1855          
Q_CAP_C0805-22UF,10V,20%,X6S,CA CH6222MEA00              PC1856          
Q_CAP_C0805-22UF,10V,20%,X6S,CA CH6222MEA00              PC1868          

----------------

Q_CAP_C0805-22UF,16V,20%,EMPTYA CH6223MEA00              PC1179_P0_3     
Q_CAP_C0805-22UF,16V,20%,EMPTYA CH6223MEA00              PC1180_P0_4     
Q_CAP_C0805-22UF,16V,20%,EMPTYA CH6223MEA00              PC1181_P0_3     
Q_CAP_C0805-22UF,16V,20%,EMPTYA CH6223MEA00              PC1182_P0_4     
Q_CAP_C0805-22UF,16V,20%,EMPTYA CH6223MEA00              PC722_P0_3      
Q_CAP_C0805-22UF,16V,20%,EMPTYA CH6223MEA00              PC723_P0_4      
Q_CAP_C0805-22UF,16V,20%,EMPTYA CH6223MEA00              PC831           
Q_CAP_C0805-22UF,16V,20%,EMPTYA CH6223MEA00              PC1247          
Q_CAP_C0805-22UF,16V,20%,EMPTYA CH6223MEA00              PC1248          

----------------

Q_CAP_C0805-22UF,16V,20%,X6S,CA CH6223MEA00              C25             
Q_CAP_C0805-22UF,16V,20%,X6S,CA CH6223MEA00              C319            
Q_CAP_C0805-22UF,16V,20%,X6S,CA CH6223MEA00              C331            
Q_CAP_C0805-22UF,16V,20%,X6S,CA CH6223MEA00              C513            
Q_CAP_C0805-22UF,16V,20%,X6S,CA CH6223MEA00              C535            
Q_CAP_C0805-22UF,16V,20%,X6S,CA CH6223MEA00              C1046           
Q_CAP_C0805-22UF,16V,20%,X6S,CA CH6223MEA00              C1047           
Q_CAP_C0805-22UF,16V,20%,X6S,CA CH6223MEA00              C1053           
Q_CAP_C0805-22UF,16V,20%,X6S,CA CH6223MEA00              C1054           
Q_CAP_C0805-22UF,16V,20%,X6S,CA CH6223MEA00              C1055           
Q_CAP_C0805-22UF,16V,20%,X6S,CA CH6223MEA00              C1061           
Q_CAP_C0805-22UF,16V,20%,X6S,CA CH6223MEA00              C1063           
Q_CAP_C0805-22UF,16V,20%,X6S,CA CH6223MEA00              C1069           
Q_CAP_C0805-22UF,16V,20%,X6S,CA CH6223MEA00              C1213           
Q_CAP_C0805-22UF,16V,20%,X6S,CA CH6223MEA00              C1232           
Q_CAP_C0805-22UF,16V,20%,X6S,CA CH6223MEA00              C1276           
Q_CAP_C0805-22UF,16V,20%,X6S,CA CH6223MEA00              C1277           
Q_CAP_C0805-22UF,16V,20%,X6S,CA CH6223MEA00              C1438           
Q_CAP_C0805-22UF,16V,20%,X6S,CA CH6223MEA00              C1439           
Q_CAP_C0805-22UF,16V,20%,X6S,CA CH6223MEA00              C1445           
Q_CAP_C0805-22UF,16V,20%,X6S,CA CH6223MEA00              C1448           
Q_CAP_C0805-22UF,16V,20%,X6S,CA CH6223MEA00              C1449           
Q_CAP_C0805-22UF,16V,20%,X6S,CA CH6223MEA00              C1455           
Q_CAP_C0805-22UF,16V,20%,X6S,CA CH6223MEA00              C1459           
Q_CAP_C0805-22UF,16V,20%,X6S,CA CH6223MEA00              C1465           
Q_CAP_C0805-22UF,16V,20%,X6S,CA CH6223MEA00              C1469           
Q_CAP_C0805-22UF,16V,20%,X6S,CA CH6223MEA00              C1475           
Q_CAP_C0805-22UF,16V,20%,X6S,CA CH6223MEA00              C1489           
Q_CAP_C0805-22UF,16V,20%,X6S,CA CH6223MEA00              C1490           
Q_CAP_C0805-22UF,16V,20%,X6S,CA CH6223MEA00              C1491           
Q_CAP_C0805-22UF,16V,20%,X6S,CA CH6223MEA00              C1492           
Q_CAP_C0805-22UF,16V,20%,X6S,CA CH6223MEA00              C1493           
Q_CAP_C0805-22UF,16V,20%,X6S,CA CH6223MEA00              C1494           
Q_CAP_C0805-22UF,16V,20%,X6S,CA CH6223MEA00              PC1199_P1_3     
Q_CAP_C0805-22UF,16V,20%,X6S,CA CH6223MEA00              PC1200_P1_4     
Q_CAP_C0805-22UF,16V,20%,X6S,CA CH6223MEA00              PC1201_P1_3     
Q_CAP_C0805-22UF,16V,20%,X6S,CA CH6223MEA00              PC1202_P1_4     
Q_CAP_C0805-22UF,16V,20%,X6S,CA CH6223MEA00              PC179           
Q_CAP_C0805-22UF,16V,20%,X6S,CA CH6223MEA00              PC180           
Q_CAP_C0805-22UF,16V,20%,X6S,CA CH6223MEA00              PC1216          
Q_CAP_C0805-22UF,16V,20%,X6S,CA CH6223MEA00              PC1217          
Q_CAP_C0805-22UF,16V,20%,X6S,CA CH6223MEA00              PC1218          
Q_CAP_C0805-22UF,16V,20%,X6S,CA CH6223MEA00              PC1259          
Q_CAP_C0805-22UF,16V,20%,X6S,CA CH6223MEA00              PC1260          
Q_CAP_C0805-22UF,16V,20%,X6S,CA CH6223MEA00              PC1261          
Q_CAP_C0805-22UF,16V,20%,X6S,CA CH6223MEA00              PC1272          
Q_CAP_C0805-22UF,16V,20%,X6S,CA CH6223MEA00              PC1273          
Q_CAP_C0805-22UF,16V,20%,X6S,CA CH6223MEA00              PC1280          
Q_CAP_C0805-22UF,16V,20%,X6S,CA CH6223MEA00              PC1281          
Q_CAP_C0805-22UF,16V,20%,X6S,CA CH6223MEA00              PC1849          
Q_CAP_C0805-22UF,16V,20%,X6S,CA CH6223MEA00              PC1850          
Q_CAP_C0805-22UF,16V,20%,X6S,CA CH6223MEA00              PC1898          
Q_CAP_C0805-22UF,16V,20%,X6S,CA CH6223MEA00              PC195_P0_1      
Q_CAP_C0805-22UF,16V,20%,X6S,CA CH6223MEA00              PC196_P0_2      
Q_CAP_C0805-22UF,16V,20%,X6S,CA CH6223MEA00              PC197_P0_1      
Q_CAP_C0805-22UF,16V,20%,X6S,CA CH6223MEA00              PC198_P0_2      
Q_CAP_C0805-22UF,16V,20%,X6S,CA CH6223MEA00              PC236_P0_8      
Q_CAP_C0805-22UF,16V,20%,X6S,CA CH6223MEA00              PC237_P0_7      
Q_CAP_C0805-22UF,16V,20%,X6S,CA CH6223MEA00              PC238_P0_8      
Q_CAP_C0805-22UF,16V,20%,X6S,CA CH6223MEA00              PC239_P0_7      
Q_CAP_C0805-22UF,16V,20%,X6S,CA CH6223MEA00              PC240_P0_8      
Q_CAP_C0805-22UF,16V,20%,X6S,CA CH6223MEA00              PC241_P0_7      
Q_CAP_C0805-22UF,16V,20%,X6S,CA CH6223MEA00              PC258_P0_6      
Q_CAP_C0805-22UF,16V,20%,X6S,CA CH6223MEA00              PC259_P0_5      
Q_CAP_C0805-22UF,16V,20%,X6S,CA CH6223MEA00              PC260_P0_6      
Q_CAP_C0805-22UF,16V,20%,X6S,CA CH6223MEA00              PC261_P0_5      
Q_CAP_C0805-22UF,16V,20%,X6S,CA CH6223MEA00              PC262_P0_6      
Q_CAP_C0805-22UF,16V,20%,X6S,CA CH6223MEA00              PC263_P0_5      
Q_CAP_C0805-22UF,16V,20%,X6S,CA CH6223MEA00              PC280_P0_4      
Q_CAP_C0805-22UF,16V,20%,X6S,CA CH6223MEA00              PC281_P0_3      
Q_CAP_C0805-22UF,16V,20%,X6S,CA CH6223MEA00              PC282_P0_4      
Q_CAP_C0805-22UF,16V,20%,X6S,CA CH6223MEA00              PC283_P0_3      
Q_CAP_C0805-22UF,16V,20%,X6S,CA CH6223MEA00              PC284_P0_4      
Q_CAP_C0805-22UF,16V,20%,X6S,CA CH6223MEA00              PC285_P0_3      
Q_CAP_C0805-22UF,16V,20%,X6S,CA CH6223MEA00              PC302_P0_2      
Q_CAP_C0805-22UF,16V,20%,X6S,CA CH6223MEA00              PC303_P0_1      
Q_CAP_C0805-22UF,16V,20%,X6S,CA CH6223MEA00              PC304_P0_2      
Q_CAP_C0805-22UF,16V,20%,X6S,CA CH6223MEA00              PC305_P0_1      
Q_CAP_C0805-22UF,16V,20%,X6S,CA CH6223MEA00              PC306_P0_2      
Q_CAP_C0805-22UF,16V,20%,X6S,CA CH6223MEA00              PC307_P0_1      
Q_CAP_C0805-22UF,16V,20%,X6S,CA CH6223MEA00              PC377           
Q_CAP_C0805-22UF,16V,20%,X6S,CA CH6223MEA00              PC378           
Q_CAP_C0805-22UF,16V,20%,X6S,CA CH6223MEA00              PC403_P1_1      
Q_CAP_C0805-22UF,16V,20%,X6S,CA CH6223MEA00              PC404_P1_2      
Q_CAP_C0805-22UF,16V,20%,X6S,CA CH6223MEA00              PC405_P1_1      
Q_CAP_C0805-22UF,16V,20%,X6S,CA CH6223MEA00              PC406_P1_2      
Q_CAP_C0805-22UF,16V,20%,X6S,CA CH6223MEA00              PC432           
Q_CAP_C0805-22UF,16V,20%,X6S,CA CH6223MEA00              PC433           
Q_CAP_C0805-22UF,16V,20%,X6S,CA CH6223MEA00              PC448_P1_1      
Q_CAP_C0805-22UF,16V,20%,X6S,CA CH6223MEA00              PC449_P1_2      
Q_CAP_C0805-22UF,16V,20%,X6S,CA CH6223MEA00              PC450_P1_1      
Q_CAP_C0805-22UF,16V,20%,X6S,CA CH6223MEA00              PC451_P1_2      
Q_CAP_C0805-22UF,16V,20%,X6S,CA CH6223MEA00              PC489_P1_8      
Q_CAP_C0805-22UF,16V,20%,X6S,CA CH6223MEA00              PC490_P1_7      
Q_CAP_C0805-22UF,16V,20%,X6S,CA CH6223MEA00              PC491_P1_8      
Q_CAP_C0805-22UF,16V,20%,X6S,CA CH6223MEA00              PC492_P1_7      
Q_CAP_C0805-22UF,16V,20%,X6S,CA CH6223MEA00              PC493_P1_8      
Q_CAP_C0805-22UF,16V,20%,X6S,CA CH6223MEA00              PC494_P1_7      
Q_CAP_C0805-22UF,16V,20%,X6S,CA CH6223MEA00              PC511_P1_6      
Q_CAP_C0805-22UF,16V,20%,X6S,CA CH6223MEA00              PC512_P1_5      
Q_CAP_C0805-22UF,16V,20%,X6S,CA CH6223MEA00              PC513_P1_6      
Q_CAP_C0805-22UF,16V,20%,X6S,CA CH6223MEA00              PC514_P1_5      
Q_CAP_C0805-22UF,16V,20%,X6S,CA CH6223MEA00              PC515_P1_6      
Q_CAP_C0805-22UF,16V,20%,X6S,CA CH6223MEA00              PC516_P1_5      
Q_CAP_C0805-22UF,16V,20%,X6S,CA CH6223MEA00              PC533_P1_4      
Q_CAP_C0805-22UF,16V,20%,X6S,CA CH6223MEA00              PC534_P1_3      
Q_CAP_C0805-22UF,16V,20%,X6S,CA CH6223MEA00              PC535_P1_4      
Q_CAP_C0805-22UF,16V,20%,X6S,CA CH6223MEA00              PC536_P1_3      
Q_CAP_C0805-22UF,16V,20%,X6S,CA CH6223MEA00              PC537_P1_4      
Q_CAP_C0805-22UF,16V,20%,X6S,CA CH6223MEA00              PC538_P1_3      
Q_CAP_C0805-22UF,16V,20%,X6S,CA CH6223MEA00              PC566_P1_2      
Q_CAP_C0805-22UF,16V,20%,X6S,CA CH6223MEA00              PC567           
Q_CAP_C0805-22UF,16V,20%,X6S,CA CH6223MEA00              PC567_P1_1      
Q_CAP_C0805-22UF,16V,20%,X6S,CA CH6223MEA00              PC568_P1_2      
Q_CAP_C0805-22UF,16V,20%,X6S,CA CH6223MEA00              PC569_P1_1      
Q_CAP_C0805-22UF,16V,20%,X6S,CA CH6223MEA00              PC570           
Q_CAP_C0805-22UF,16V,20%,X6S,CA CH6223MEA00              PC570_P1_2      
Q_CAP_C0805-22UF,16V,20%,X6S,CA CH6223MEA00              PC571           
Q_CAP_C0805-22UF,16V,20%,X6S,CA CH6223MEA00              PC571_P1_1      
Q_CAP_C0805-22UF,16V,20%,X6S,CA CH6223MEA00              PC576           
Q_CAP_C0805-22UF,16V,20%,X6S,CA CH6223MEA00              PC608_P0_1      
Q_CAP_C0805-22UF,16V,20%,X6S,CA CH6223MEA00              PC609_P0_2      
Q_CAP_C0805-22UF,16V,20%,X6S,CA CH6223MEA00              PC610_P0_1      
Q_CAP_C0805-22UF,16V,20%,X6S,CA CH6223MEA00              PC611_P0_2      
Q_CAP_C0805-22UF,16V,20%,X6S,CA CH6223MEA00              PC71            
Q_CAP_C0805-22UF,16V,20%,X6S,CA CH6223MEA00              PC637           
Q_CAP_C0805-22UF,16V,20%,X6S,CA CH6223MEA00              PC638           
Q_CAP_C0805-22UF,16V,20%,X6S,CA CH6223MEA00              PC720_P0_1      
Q_CAP_C0805-22UF,16V,20%,X6S,CA CH6223MEA00              PC721_P0_2      
Q_CAP_C0805-22UF,16V,20%,X6S,CA CH6223MEA00              PC724_P1_1      
Q_CAP_C0805-22UF,16V,20%,X6S,CA CH6223MEA00              PC725_P1_2      
Q_CAP_C0805-22UF,16V,20%,X6S,CA CH6223MEA00              PC726_P1_3      
Q_CAP_C0805-22UF,16V,20%,X6S,CA CH6223MEA00              PC727_P1_4      

----------------

Q_CAP_C0805-22UF,25V,20%,X5R,CA CH6224M9A00              C633            

----------------

Q_CAP_DIFFBUS_C0201-DIFF BUS_0A CH4221MEE01              C139            
Q_CAP_DIFFBUS_C0201-DIFF BUS_0A CH4221MEE01              C140            
Q_CAP_DIFFBUS_C0201-DIFF BUS_0A CH4221MEE01              C141            
Q_CAP_DIFFBUS_C0201-DIFF BUS_0A CH4221MEE01              C142            
Q_CAP_DIFFBUS_C0201-DIFF BUS_0A CH4221MEE01              C143            
Q_CAP_DIFFBUS_C0201-DIFF BUS_0A CH4221MEE01              C144            
Q_CAP_DIFFBUS_C0201-DIFF BUS_0A CH4221MEE01              C145            
Q_CAP_DIFFBUS_C0201-DIFF BUS_0A CH4221MEE01              C146            
Q_CAP_DIFFBUS_C0201-DIFF BUS_0A CH4221MEE01              C147            
Q_CAP_DIFFBUS_C0201-DIFF BUS_0A CH4221MEE01              C148            
Q_CAP_DIFFBUS_C0201-DIFF BUS_0A CH4221MEE01              C149            
Q_CAP_DIFFBUS_C0201-DIFF BUS_0A CH4221MEE01              C150            
Q_CAP_DIFFBUS_C0201-DIFF BUS_0A CH4221MEE01              C151            
Q_CAP_DIFFBUS_C0201-DIFF BUS_0A CH4221MEE01              C152            
Q_CAP_DIFFBUS_C0201-DIFF BUS_0A CH4221MEE01              C153            
Q_CAP_DIFFBUS_C0201-DIFF BUS_0A CH4221MEE01              C154            
Q_CAP_DIFFBUS_C0201-DIFF BUS_0A CH4221MEE01              C155            
Q_CAP_DIFFBUS_C0201-DIFF BUS_0A CH4221MEE01              C156            
Q_CAP_DIFFBUS_C0201-DIFF BUS_0A CH4221MEE01              C157            
Q_CAP_DIFFBUS_C0201-DIFF BUS_0A CH4221MEE01              C158            
Q_CAP_DIFFBUS_C0201-DIFF BUS_0A CH4221MEE01              C159            
Q_CAP_DIFFBUS_C0201-DIFF BUS_0A CH4221MEE01              C160            
Q_CAP_DIFFBUS_C0201-DIFF BUS_0A CH4221MEE01              C161            
Q_CAP_DIFFBUS_C0201-DIFF BUS_0A CH4221MEE01              C162            
Q_CAP_DIFFBUS_C0201-DIFF BUS_0A CH4221MEE01              C163            
Q_CAP_DIFFBUS_C0201-DIFF BUS_0A CH4221MEE01              C164            
Q_CAP_DIFFBUS_C0201-DIFF BUS_0A CH4221MEE01              C165            
Q_CAP_DIFFBUS_C0201-DIFF BUS_0A CH4221MEE01              C166            
Q_CAP_DIFFBUS_C0201-DIFF BUS_0A CH4221MEE01              C167            
Q_CAP_DIFFBUS_C0201-DIFF BUS_0A CH4221MEE01              C168            
Q_CAP_DIFFBUS_C0201-DIFF BUS_0A CH4221MEE01              C169            
Q_CAP_DIFFBUS_C0201-DIFF BUS_0A CH4221MEE01              C170            
Q_CAP_DIFFBUS_C0201-DIFF BUS_0A CH4221MEE01              C678            
Q_CAP_DIFFBUS_C0201-DIFF BUS_0A CH4221MEE01              C679            
Q_CAP_DIFFBUS_C0201-DIFF BUS_0A CH4221MEE01              C680            
Q_CAP_DIFFBUS_C0201-DIFF BUS_0A CH4221MEE01              C681            
Q_CAP_DIFFBUS_C0201-DIFF BUS_0A CH4221MEE01              C682            
Q_CAP_DIFFBUS_C0201-DIFF BUS_0A CH4221MEE01              C683            
Q_CAP_DIFFBUS_C0201-DIFF BUS_0A CH4221MEE01              C684            
Q_CAP_DIFFBUS_C0201-DIFF BUS_0A CH4221MEE01              C685            
Q_CAP_DIFFBUS_C0201-DIFF BUS_0A CH4221MEE01              C686            
Q_CAP_DIFFBUS_C0201-DIFF BUS_0A CH4221MEE01              C687            
Q_CAP_DIFFBUS_C0201-DIFF BUS_0A CH4221MEE01              C688            
Q_CAP_DIFFBUS_C0201-DIFF BUS_0A CH4221MEE01              C689            
Q_CAP_DIFFBUS_C0201-DIFF BUS_0A CH4221MEE01              C690            
Q_CAP_DIFFBUS_C0201-DIFF BUS_0A CH4221MEE01              C691            
Q_CAP_DIFFBUS_C0201-DIFF BUS_0A CH4221MEE01              C692            
Q_CAP_DIFFBUS_C0201-DIFF BUS_0A CH4221MEE01              C693            
Q_CAP_DIFFBUS_C0201-DIFF BUS_0A CH4221MEE01              C694            
Q_CAP_DIFFBUS_C0201-DIFF BUS_0A CH4221MEE01              C695            
Q_CAP_DIFFBUS_C0201-DIFF BUS_0A CH4221MEE01              C696            
Q_CAP_DIFFBUS_C0201-DIFF BUS_0A CH4221MEE01              C697            
Q_CAP_DIFFBUS_C0201-DIFF BUS_0A CH4221MEE01              C698            
Q_CAP_DIFFBUS_C0201-DIFF BUS_0A CH4221MEE01              C699            
Q_CAP_DIFFBUS_C0201-DIFF BUS_0A CH4221MEE01              C700            
Q_CAP_DIFFBUS_C0201-DIFF BUS_0A CH4221MEE01              C701            
Q_CAP_DIFFBUS_C0201-DIFF BUS_0A CH4221MEE01              C702            
Q_CAP_DIFFBUS_C0201-DIFF BUS_0A CH4221MEE01              C703            
Q_CAP_DIFFBUS_C0201-DIFF BUS_0A CH4221MEE01              C704            
Q_CAP_DIFFBUS_C0201-DIFF BUS_0A CH4221MEE01              C705            
Q_CAP_DIFFBUS_C0201-DIFF BUS_0A CH4221MEE01              C706            
Q_CAP_DIFFBUS_C0201-DIFF BUS_0A CH4221MEE01              C707            
Q_CAP_DIFFBUS_C0201-DIFF BUS_0A CH4221MEE01              C708            
Q_CAP_DIFFBUS_C0201-DIFF BUS_0A CH4221MEE01              C709            
Q_CAP_DIFFBUS_C0201-DIFF BUS_0A CH4221MEE01              C710            
Q_CAP_DIFFBUS_C0201-DIFF BUS_0A CH4221MEE01              C711            
Q_CAP_DIFFBUS_C0201-DIFF BUS_0A CH4221MEE01              C712            
Q_CAP_DIFFBUS_C0201-DIFF BUS_0A CH4221MEE01              C713            
Q_CAP_DIFFBUS_C0201-DIFF BUS_0A CH4221MEE01              C714            
Q_CAP_DIFFBUS_C0201-DIFF BUS_0A CH4221MEE01              C715            
Q_CAP_DIFFBUS_C0201-DIFF BUS_0A CH4221MEE01              C716            
Q_CAP_DIFFBUS_C0201-DIFF BUS_0A CH4221MEE01              C717            
Q_CAP_DIFFBUS_C0201-DIFF BUS_0A CH4221MEE01              C718            
Q_CAP_DIFFBUS_C0201-DIFF BUS_0A CH4221MEE01              C719            
Q_CAP_DIFFBUS_C0201-DIFF BUS_0A CH4221MEE01              C720            
Q_CAP_DIFFBUS_C0201-DIFF BUS_0A CH4221MEE01              C721            
Q_CAP_DIFFBUS_C0201-DIFF BUS_0A CH4221MEE01              C722            
Q_CAP_DIFFBUS_C0201-DIFF BUS_0A CH4221MEE01              C723            
Q_CAP_DIFFBUS_C0201-DIFF BUS_0A CH4221MEE01              C724            
Q_CAP_DIFFBUS_C0201-DIFF BUS_0A CH4221MEE01              C725            
Q_CAP_DIFFBUS_C0201-DIFF BUS_0A CH4221MEE01              C726            
Q_CAP_DIFFBUS_C0201-DIFF BUS_0A CH4221MEE01              C727            
Q_CAP_DIFFBUS_C0201-DIFF BUS_0A CH4221MEE01              C728            
Q_CAP_DIFFBUS_C0201-DIFF BUS_0A CH4221MEE01              C729            
Q_CAP_DIFFBUS_C0201-DIFF BUS_0A CH4221MEE01              C730            
Q_CAP_DIFFBUS_C0201-DIFF BUS_0A CH4221MEE01              C731            
Q_CAP_DIFFBUS_C0201-DIFF BUS_0A CH4221MEE01              C732            
Q_CAP_DIFFBUS_C0201-DIFF BUS_0A CH4221MEE01              C733            
Q_CAP_DIFFBUS_C0201-DIFF BUS_0A CH4221MEE01              C734            
Q_CAP_DIFFBUS_C0201-DIFF BUS_0A CH4221MEE01              C735            
Q_CAP_DIFFBUS_C0201-DIFF BUS_0A CH4221MEE01              C736            
Q_CAP_DIFFBUS_C0201-DIFF BUS_0A CH4221MEE01              C737            
Q_CAP_DIFFBUS_C0201-DIFF BUS_0A CH4221MEE01              C738            
Q_CAP_DIFFBUS_C0201-DIFF BUS_0A CH4221MEE01              C739            
Q_CAP_DIFFBUS_C0201-DIFF BUS_0A CH4221MEE01              C740            
Q_CAP_DIFFBUS_C0201-DIFF BUS_0A CH4221MEE01              C741            
Q_CAP_DIFFBUS_C0201-DIFF BUS_0A CH4221MEE01              C742            
Q_CAP_DIFFBUS_C0201-DIFF BUS_0A CH4221MEE01              C743            
Q_CAP_DIFFBUS_C0201-DIFF BUS_0A CH4221MEE01              C744            
Q_CAP_DIFFBUS_C0201-DIFF BUS_0A CH4221MEE01              C745            
Q_CAP_DIFFBUS_C0201-DIFF BUS_0A CH4221MEE01              C746            
Q_CAP_DIFFBUS_C0201-DIFF BUS_0A CH4221MEE01              C747            
Q_CAP_DIFFBUS_C0201-DIFF BUS_0A CH4221MEE01              C748            
Q_CAP_DIFFBUS_C0201-DIFF BUS_0A CH4221MEE01              C749            
Q_CAP_DIFFBUS_C0201-DIFF BUS_0A CH4221MEE01              C750            
Q_CAP_DIFFBUS_C0201-DIFF BUS_0A CH4221MEE01              C751            
Q_CAP_DIFFBUS_C0201-DIFF BUS_0A CH4221MEE01              C752            
Q_CAP_DIFFBUS_C0201-DIFF BUS_0A CH4221MEE01              C753            
Q_CAP_DIFFBUS_C0201-DIFF BUS_0A CH4221MEE01              C754            
Q_CAP_DIFFBUS_C0201-DIFF BUS_0A CH4221MEE01              C755            
Q_CAP_DIFFBUS_C0201-DIFF BUS_0A CH4221MEE01              C756            
Q_CAP_DIFFBUS_C0201-DIFF BUS_0A CH4221MEE01              C757            
Q_CAP_DIFFBUS_C0201-DIFF BUS_0A CH4221MEE01              C758            
Q_CAP_DIFFBUS_C0201-DIFF BUS_0A CH4221MEE01              C759            
Q_CAP_DIFFBUS_C0201-DIFF BUS_0A CH4221MEE01              C760            
Q_CAP_DIFFBUS_C0201-DIFF BUS_0A CH4221MEE01              C761            
Q_CAP_DIFFBUS_C0201-DIFF BUS_0A CH4221MEE01              C762            
Q_CAP_DIFFBUS_C0201-DIFF BUS_0A CH4221MEE01              C763            
Q_CAP_DIFFBUS_C0201-DIFF BUS_0A CH4221MEE01              C764            
Q_CAP_DIFFBUS_C0201-DIFF BUS_0A CH4221MEE01              C765            
Q_CAP_DIFFBUS_C0201-DIFF BUS_0A CH4221MEE01              C766            
Q_CAP_DIFFBUS_C0201-DIFF BUS_0A CH4221MEE01              C767            
Q_CAP_DIFFBUS_C0201-DIFF BUS_0A CH4221MEE01              C768            
Q_CAP_DIFFBUS_C0201-DIFF BUS_0A CH4221MEE01              C769            
Q_CAP_DIFFBUS_C0201-DIFF BUS_0A CH4221MEE01              C770            
Q_CAP_DIFFBUS_C0201-DIFF BUS_0A CH4221MEE01              C771            
Q_CAP_DIFFBUS_C0201-DIFF BUS_0A CH4221MEE01              C772            
Q_CAP_DIFFBUS_C0201-DIFF BUS_0A CH4221MEE01              C773            
Q_CAP_DIFFBUS_C0201-DIFF BUS_0A CH4221MEE01              C806            
Q_CAP_DIFFBUS_C0201-DIFF BUS_0A CH4221MEE01              C807            
Q_CAP_DIFFBUS_C0201-DIFF BUS_0A CH4221MEE01              C808            
Q_CAP_DIFFBUS_C0201-DIFF BUS_0A CH4221MEE01              C809            
Q_CAP_DIFFBUS_C0201-DIFF BUS_0A CH4221MEE01              C810            
Q_CAP_DIFFBUS_C0201-DIFF BUS_0A CH4221MEE01              C811            
Q_CAP_DIFFBUS_C0201-DIFF BUS_0A CH4221MEE01              C812            
Q_CAP_DIFFBUS_C0201-DIFF BUS_0A CH4221MEE01              C813            
Q_CAP_DIFFBUS_C0201-DIFF BUS_0A CH4221MEE01              C814            
Q_CAP_DIFFBUS_C0201-DIFF BUS_0A CH4221MEE01              C815            
Q_CAP_DIFFBUS_C0201-DIFF BUS_0A CH4221MEE01              C816            
Q_CAP_DIFFBUS_C0201-DIFF BUS_0A CH4221MEE01              C817            
Q_CAP_DIFFBUS_C0201-DIFF BUS_0A CH4221MEE01              C818            
Q_CAP_DIFFBUS_C0201-DIFF BUS_0A CH4221MEE01              C819            
Q_CAP_DIFFBUS_C0201-DIFF BUS_0A CH4221MEE01              C820            
Q_CAP_DIFFBUS_C0201-DIFF BUS_0A CH4221MEE01              C821            
Q_CAP_DIFFBUS_C0201-DIFF BUS_0A CH4221MEE01              C822            
Q_CAP_DIFFBUS_C0201-DIFF BUS_0A CH4221MEE01              C823            
Q_CAP_DIFFBUS_C0201-DIFF BUS_0A CH4221MEE01              C824            
Q_CAP_DIFFBUS_C0201-DIFF BUS_0A CH4221MEE01              C825            
Q_CAP_DIFFBUS_C0201-DIFF BUS_0A CH4221MEE01              C826            
Q_CAP_DIFFBUS_C0201-DIFF BUS_0A CH4221MEE01              C827            
Q_CAP_DIFFBUS_C0201-DIFF BUS_0A CH4221MEE01              C828            
Q_CAP_DIFFBUS_C0201-DIFF BUS_0A CH4221MEE01              C829            
Q_CAP_DIFFBUS_C0201-DIFF BUS_0A CH4221MEE01              C830            
Q_CAP_DIFFBUS_C0201-DIFF BUS_0A CH4221MEE01              C831            
Q_CAP_DIFFBUS_C0201-DIFF BUS_0A CH4221MEE01              C832            
Q_CAP_DIFFBUS_C0201-DIFF BUS_0A CH4221MEE01              C833            
Q_CAP_DIFFBUS_C0201-DIFF BUS_0A CH4221MEE01              C834            
Q_CAP_DIFFBUS_C0201-DIFF BUS_0A CH4221MEE01              C835            
Q_CAP_DIFFBUS_C0201-DIFF BUS_0A CH4221MEE01              C836            
Q_CAP_DIFFBUS_C0201-DIFF BUS_0A CH4221MEE01              C837            
Q_CAP_DIFFBUS_C0201-DIFF BUS_0A CH4221MEE01              C838            
Q_CAP_DIFFBUS_C0201-DIFF BUS_0A CH4221MEE01              C839            
Q_CAP_DIFFBUS_C0201-DIFF BUS_0A CH4221MEE01              C840            
Q_CAP_DIFFBUS_C0201-DIFF BUS_0A CH4221MEE01              C841            
Q_CAP_DIFFBUS_C0201-DIFF BUS_0A CH4221MEE01              C842            
Q_CAP_DIFFBUS_C0201-DIFF BUS_0A CH4221MEE01              C843            
Q_CAP_DIFFBUS_C0201-DIFF BUS_0A CH4221MEE01              C844            
Q_CAP_DIFFBUS_C0201-DIFF BUS_0A CH4221MEE01              C845            
Q_CAP_DIFFBUS_C0201-DIFF BUS_0A CH4221MEE01              C846            
Q_CAP_DIFFBUS_C0201-DIFF BUS_0A CH4221MEE01              C847            
Q_CAP_DIFFBUS_C0201-DIFF BUS_0A CH4221MEE01              C848            
Q_CAP_DIFFBUS_C0201-DIFF BUS_0A CH4221MEE01              C849            
Q_CAP_DIFFBUS_C0201-DIFF BUS_0A CH4221MEE01              C850            
Q_CAP_DIFFBUS_C0201-DIFF BUS_0A CH4221MEE01              C851            
Q_CAP_DIFFBUS_C0201-DIFF BUS_0A CH4221MEE01              C852            
Q_CAP_DIFFBUS_C0201-DIFF BUS_0A CH4221MEE01              C853            
Q_CAP_DIFFBUS_C0201-DIFF BUS_0A CH4221MEE01              C854            
Q_CAP_DIFFBUS_C0201-DIFF BUS_0A CH4221MEE01              C855            
Q_CAP_DIFFBUS_C0201-DIFF BUS_0A CH4221MEE01              C856            
Q_CAP_DIFFBUS_C0201-DIFF BUS_0A CH4221MEE01              C857            
Q_CAP_DIFFBUS_C0201-DIFF BUS_0A CH4221MEE01              C858            
Q_CAP_DIFFBUS_C0201-DIFF BUS_0A CH4221MEE01              C859            
Q_CAP_DIFFBUS_C0201-DIFF BUS_0A CH4221MEE01              C860            
Q_CAP_DIFFBUS_C0201-DIFF BUS_0A CH4221MEE01              C861            
Q_CAP_DIFFBUS_C0201-DIFF BUS_0A CH4221MEE01              C862            
Q_CAP_DIFFBUS_C0201-DIFF BUS_0A CH4221MEE01              C863            
Q_CAP_DIFFBUS_C0201-DIFF BUS_0A CH4221MEE01              C864            
Q_CAP_DIFFBUS_C0201-DIFF BUS_0A CH4221MEE01              C865            
Q_CAP_DIFFBUS_C0201-DIFF BUS_0A CH4221MEE01              C866            
Q_CAP_DIFFBUS_C0201-DIFF BUS_0A CH4221MEE01              C867            
Q_CAP_DIFFBUS_C0201-DIFF BUS_0A CH4221MEE01              C868            
Q_CAP_DIFFBUS_C0201-DIFF BUS_0A CH4221MEE01              C869            
Q_CAP_DIFFBUS_C0201-DIFF BUS_0A CH4221MEE01              C870            
Q_CAP_DIFFBUS_C0201-DIFF BUS_0A CH4221MEE01              C871            
Q_CAP_DIFFBUS_C0201-DIFF BUS_0A CH4221MEE01              C872            
Q_CAP_DIFFBUS_C0201-DIFF BUS_0A CH4221MEE01              C873            
Q_CAP_DIFFBUS_C0201-DIFF BUS_0A CH4221MEE01              C874            
Q_CAP_DIFFBUS_C0201-DIFF BUS_0A CH4221MEE01              C875            
Q_CAP_DIFFBUS_C0201-DIFF BUS_0A CH4221MEE01              C876            
Q_CAP_DIFFBUS_C0201-DIFF BUS_0A CH4221MEE01              C877            
Q_CAP_DIFFBUS_C0201-DIFF BUS_0A CH4221MEE01              C878            
Q_CAP_DIFFBUS_C0201-DIFF BUS_0A CH4221MEE01              C879            
Q_CAP_DIFFBUS_C0201-DIFF BUS_0A CH4221MEE01              C880            
Q_CAP_DIFFBUS_C0201-DIFF BUS_0A CH4221MEE01              C881            
Q_CAP_DIFFBUS_C0201-DIFF BUS_0A CH4221MEE01              C882            
Q_CAP_DIFFBUS_C0201-DIFF BUS_0A CH4221MEE01              C883            
Q_CAP_DIFFBUS_C0201-DIFF BUS_0A CH4221MEE01              C884            
Q_CAP_DIFFBUS_C0201-DIFF BUS_0A CH4221MEE01              C885            
Q_CAP_DIFFBUS_C0201-DIFF BUS_0A CH4221MEE01              C886            
Q_CAP_DIFFBUS_C0201-DIFF BUS_0A CH4221MEE01              C887            
Q_CAP_DIFFBUS_C0201-DIFF BUS_0A CH4221MEE01              C888            
Q_CAP_DIFFBUS_C0201-DIFF BUS_0A CH4221MEE01              C889            
Q_CAP_DIFFBUS_C0201-DIFF BUS_0A CH4221MEE01              C890            
Q_CAP_DIFFBUS_C0201-DIFF BUS_0A CH4221MEE01              C891            
Q_CAP_DIFFBUS_C0201-DIFF BUS_0A CH4221MEE01              C892            
Q_CAP_DIFFBUS_C0201-DIFF BUS_0A CH4221MEE01              C893            
Q_CAP_DIFFBUS_C0201-DIFF BUS_0A CH4221MEE01              C894            
Q_CAP_DIFFBUS_C0201-DIFF BUS_0A CH4221MEE01              C895            
Q_CAP_DIFFBUS_C0201-DIFF BUS_0A CH4221MEE01              C896            
Q_CAP_DIFFBUS_C0201-DIFF BUS_0A CH4221MEE01              C897            
Q_CAP_DIFFBUS_C0201-DIFF BUS_0A CH4221MEE01              C898            
Q_CAP_DIFFBUS_C0201-DIFF BUS_0A CH4221MEE01              C899            
Q_CAP_DIFFBUS_C0201-DIFF BUS_0A CH4221MEE01              C900            
Q_CAP_DIFFBUS_C0201-DIFF BUS_0A CH4221MEE01              C901            
Q_CAP_DIFFBUS_C0201-DIFF BUS_0A CH4221MEE01              C902            
Q_CAP_DIFFBUS_C0201-DIFF BUS_0A CH4221MEE01              C903            
Q_CAP_DIFFBUS_C0201-DIFF BUS_0A CH4221MEE01              C904            
Q_CAP_DIFFBUS_C0201-DIFF BUS_0A CH4221MEE01              C905            
Q_CAP_DIFFBUS_C0201-DIFF BUS_0A CH4221MEE01              C906            
Q_CAP_DIFFBUS_C0201-DIFF BUS_0A CH4221MEE01              C907            
Q_CAP_DIFFBUS_C0201-DIFF BUS_0A CH4221MEE01              C908            
Q_CAP_DIFFBUS_C0201-DIFF BUS_0A CH4221MEE01              C909            
Q_CAP_DIFFBUS_C0201-DIFF BUS_0A CH4221MEE01              C910            
Q_CAP_DIFFBUS_C0201-DIFF BUS_0A CH4221MEE01              C911            
Q_CAP_DIFFBUS_C0201-DIFF BUS_0A CH4221MEE01              C912            
Q_CAP_DIFFBUS_C0201-DIFF BUS_0A CH4221MEE01              C913            
Q_CAP_DIFFBUS_C0201-DIFF BUS_0A CH4221MEE01              C914            
Q_CAP_DIFFBUS_C0201-DIFF BUS_0A CH4221MEE01              C915            
Q_CAP_DIFFBUS_C0201-DIFF BUS_0A CH4221MEE01              C916            
Q_CAP_DIFFBUS_C0201-DIFF BUS_0A CH4221MEE01              C917            
Q_CAP_DIFFBUS_C0201-DIFF BUS_0A CH4221MEE01              C918            
Q_CAP_DIFFBUS_C0201-DIFF BUS_0A CH4221MEE01              C919            
Q_CAP_DIFFBUS_C0201-DIFF BUS_0A CH4221MEE01              C920            
Q_CAP_DIFFBUS_C0201-DIFF BUS_0A CH4221MEE01              C921            
Q_CAP_DIFFBUS_C0201-DIFF BUS_0A CH4221MEE01              C922            
Q_CAP_DIFFBUS_C0201-DIFF BUS_0A CH4221MEE01              C923            
Q_CAP_DIFFBUS_C0201-DIFF BUS_0A CH4221MEE01              C924            
Q_CAP_DIFFBUS_C0201-DIFF BUS_0A CH4221MEE01              C925            
Q_CAP_DIFFBUS_C0201-DIFF BUS_0A CH4221MEE01              C926            
Q_CAP_DIFFBUS_C0201-DIFF BUS_0A CH4221MEE01              C927            
Q_CAP_DIFFBUS_C0201-DIFF BUS_0A CH4221MEE01              C928            
Q_CAP_DIFFBUS_C0201-DIFF BUS_0A CH4221MEE01              C929            
Q_CAP_DIFFBUS_C0201-DIFF BUS_0A CH4221MEE01              C930            
Q_CAP_DIFFBUS_C0201-DIFF BUS_0A CH4221MEE01              C931            
Q_CAP_DIFFBUS_C0201-DIFF BUS_0A CH4221MEE01              C932            
Q_CAP_DIFFBUS_C0201-DIFF BUS_0A CH4221MEE01              C933            
Q_CAP_DIFFBUS_C0201-DIFF BUS_0A CH4221MEE01              C934            
Q_CAP_DIFFBUS_C0201-DIFF BUS_0A CH4221MEE01              C935            
Q_CAP_DIFFBUS_C0201-DIFF BUS_0A CH4221MEE01              C936            
Q_CAP_DIFFBUS_C0201-DIFF BUS_0A CH4221MEE01              C937            
Q_CAP_DIFFBUS_C0201-DIFF BUS_0A CH4221MEE01              C938            
Q_CAP_DIFFBUS_C0201-DIFF BUS_0A CH4221MEE01              C939            
Q_CAP_DIFFBUS_C0201-DIFF BUS_0A CH4221MEE01              C940            
Q_CAP_DIFFBUS_C0201-DIFF BUS_0A CH4221MEE01              C941            
Q_CAP_DIFFBUS_C0201-DIFF BUS_0A CH4221MEE01              C942            
Q_CAP_DIFFBUS_C0201-DIFF BUS_0A CH4221MEE01              C943            
Q_CAP_DIFFBUS_C0201-DIFF BUS_0A CH4221MEE01              C944            
Q_CAP_DIFFBUS_C0201-DIFF BUS_0A CH4221MEE01              C945            
Q_CAP_DIFFBUS_C0201-DIFF BUS_0A CH4221MEE01              C946            
Q_CAP_DIFFBUS_C0201-DIFF BUS_0A CH4221MEE01              C947            
Q_CAP_DIFFBUS_C0201-DIFF BUS_0A CH4221MEE01              C948            
Q_CAP_DIFFBUS_C0201-DIFF BUS_0A CH4221MEE01              C949            
Q_CAP_DIFFBUS_C0201-DIFF BUS_0A CH4221MEE01              C950            
Q_CAP_DIFFBUS_C0201-DIFF BUS_0A CH4221MEE01              C951            
Q_CAP_DIFFBUS_C0201-DIFF BUS_0A CH4221MEE01              C952            
Q_CAP_DIFFBUS_C0201-DIFF BUS_0A CH4221MEE01              C953            
Q_CAP_DIFFBUS_C0201-DIFF BUS_0A CH4221MEE01              C954            
Q_CAP_DIFFBUS_C0201-DIFF BUS_0A CH4221MEE01              C955            
Q_CAP_DIFFBUS_C0201-DIFF BUS_0A CH4221MEE01              C956            
Q_CAP_DIFFBUS_C0201-DIFF BUS_0A CH4221MEE01              C957            
Q_CAP_DIFFBUS_C0201-DIFF BUS_0A CH4221MEE01              C958            
Q_CAP_DIFFBUS_C0201-DIFF BUS_0A CH4221MEE01              C959            
Q_CAP_DIFFBUS_C0201-DIFF BUS_0A CH4221MEE01              C960            
Q_CAP_DIFFBUS_C0201-DIFF BUS_0A CH4221MEE01              C961            
Q_CAP_DIFFBUS_C0201-DIFF BUS_0A CH4221MEE01              C962            
Q_CAP_DIFFBUS_C0201-DIFF BUS_0A CH4221MEE01              C963            
Q_CAP_DIFFBUS_C0201-DIFF BUS_0A CH4221MEE01              C964            
Q_CAP_DIFFBUS_C0201-DIFF BUS_0A CH4221MEE01              C965            
Q_CAP_DIFFBUS_C0201-DIFF BUS_0A CH4221MEE01              C1096           
Q_CAP_DIFFBUS_C0201-DIFF BUS_0A CH4221MEE01              C1097           
Q_CAP_DIFFBUS_C0201-DIFF BUS_0A CH4221MEE01              C1098           
Q_CAP_DIFFBUS_C0201-DIFF BUS_0A CH4221MEE01              C1099           
Q_CAP_DIFFBUS_C0201-DIFF BUS_0A CH4221MEE01              C1100           
Q_CAP_DIFFBUS_C0201-DIFF BUS_0A CH4221MEE01              C1101           
Q_CAP_DIFFBUS_C0201-DIFF BUS_0A CH4221MEE01              C1102           
Q_CAP_DIFFBUS_C0201-DIFF BUS_0A CH4221MEE01              C1103           
Q_CAP_DIFFBUS_C0201-DIFF BUS_0A CH4221MEE01              C1104           
Q_CAP_DIFFBUS_C0201-DIFF BUS_0A CH4221MEE01              C1105           
Q_CAP_DIFFBUS_C0201-DIFF BUS_0A CH4221MEE01              C1516           
Q_CAP_DIFFBUS_C0201-DIFF BUS_0A CH4221MEE01              C1517           
Q_CAP_DIFFBUS_C0201-DIFF BUS_0A CH4221MEE01              C1518           
Q_CAP_DIFFBUS_C0201-DIFF BUS_0A CH4221MEE01              C1519           
Q_CAP_DIFFBUS_C0201-DIFF BUS_0A CH4221MEE01              C1520           
Q_CAP_DIFFBUS_C0201-DIFF BUS_0A CH4221MEE01              C1521           
Q_CAP_DIFFBUS_C0201-DIFF BUS_0A CH4221MEE01              C1522           
Q_CAP_DIFFBUS_C0201-DIFF BUS_0A CH4221MEE01              C1523           
Q_CAP_DIFFBUS_C0201-DIFF BUS_0A CH4221MEE01              C1524           
Q_CAP_DIFFBUS_C0201-DIFF BUS_0A CH4221MEE01              C1525           
Q_CAP_DIFFBUS_C0201-DIFF BUS_0A CH4221MEE01              C1526           
Q_CAP_DIFFBUS_C0201-DIFF BUS_0A CH4221MEE01              C1527           
Q_CAP_DIFFBUS_C0201-DIFF BUS_0A CH4221MEE01              C1528           
Q_CAP_DIFFBUS_C0201-DIFF BUS_0A CH4221MEE01              C1529           
Q_CAP_DIFFBUS_C0201-DIFF BUS_0A CH4221MEE01              C1530           
Q_CAP_DIFFBUS_C0201-DIFF BUS_0A CH4221MEE01              C1531           
Q_CAP_DIFFBUS_C0201-DIFF BUS_0A CH4221MEE01              C1532           
Q_CAP_DIFFBUS_C0201-DIFF BUS_0A CH4221MEE01              C1533           
Q_CAP_DIFFBUS_C0201-DIFF BUS_0A CH4221MEE01              C1534           
Q_CAP_DIFFBUS_C0201-DIFF BUS_0A CH4221MEE01              C1535           
Q_CAP_DIFFBUS_C0201-DIFF BUS_0A CH4221MEE01              C1536           
Q_CAP_DIFFBUS_C0201-DIFF BUS_0A CH4221MEE01              C1537           
Q_CAP_DIFFBUS_C0201-DIFF BUS_0A CH4221MEE01              C1538           
Q_CAP_DIFFBUS_C0201-DIFF BUS_0A CH4221MEE01              C1539           
Q_CAP_DIFFBUS_C0201-DIFF BUS_0A CH4221MEE01              C1540           
Q_CAP_DIFFBUS_C0201-DIFF BUS_0A CH4221MEE01              C1541           
Q_CAP_DIFFBUS_C0201-DIFF BUS_0A CH4221MEE01              C1542           
Q_CAP_DIFFBUS_C0201-DIFF BUS_0A CH4221MEE01              C1543           
Q_CAP_DIFFBUS_C0201-DIFF BUS_0A CH4221MEE01              C1544           
Q_CAP_DIFFBUS_C0201-DIFF BUS_0A CH4221MEE01              C1545           
Q_CAP_DIFFBUS_C0201-DIFF BUS_0A CH4221MEE01              C1546           
Q_CAP_DIFFBUS_C0201-DIFF BUS_0A CH4221MEE01              C1547           
Q_CAP_DIFFBUS_C0201-DIFF BUS_0A CH4221MEE01              C1548           
Q_CAP_DIFFBUS_C0201-DIFF BUS_0A CH4221MEE01              C1549           
Q_CAP_DIFFBUS_C0201-DIFF BUS_0A CH4221MEE01              C1550           
Q_CAP_DIFFBUS_C0201-DIFF BUS_0A CH4221MEE01              C1551           
Q_CAP_DIFFBUS_C0201-DIFF BUS_0A CH4221MEE01              C1552           
Q_CAP_DIFFBUS_C0201-DIFF BUS_0A CH4221MEE01              C1553           
Q_CAP_DIFFBUS_C0201-DIFF BUS_0A CH4221MEE01              C1554           
Q_CAP_DIFFBUS_C0201-DIFF BUS_0A CH4221MEE01              C1555           
Q_CAP_DIFFBUS_C0201-DIFF BUS_0A CH4221MEE01              C1556           
Q_CAP_DIFFBUS_C0201-DIFF BUS_0A CH4221MEE01              C1557           
Q_CAP_DIFFBUS_C0201-DIFF BUS_0A CH4221MEE01              C1558           
Q_CAP_DIFFBUS_C0201-DIFF BUS_0A CH4221MEE01              C1559           
Q_CAP_DIFFBUS_C0201-DIFF BUS_0A CH4221MEE01              C1560           
Q_CAP_DIFFBUS_C0201-DIFF BUS_0A CH4221MEE01              C1561           
Q_CAP_DIFFBUS_C0201-DIFF BUS_0A CH4221MEE01              C1562           
Q_CAP_DIFFBUS_C0201-DIFF BUS_0A CH4221MEE01              C1563           
Q_CAP_DIFFBUS_C0201-DIFF BUS_0A CH4221MEE01              C1564           
Q_CAP_DIFFBUS_C0201-DIFF BUS_0A CH4221MEE01              C1565           
Q_CAP_DIFFBUS_C0201-DIFF BUS_0A CH4221MEE01              C1566           
Q_CAP_DIFFBUS_C0201-DIFF BUS_0A CH4221MEE01              C1567           
Q_CAP_DIFFBUS_C0201-DIFF BUS_0A CH4221MEE01              C1568           
Q_CAP_DIFFBUS_C0201-DIFF BUS_0A CH4221MEE01              C1569           
Q_CAP_DIFFBUS_C0201-DIFF BUS_0A CH4221MEE01              C1570           
Q_CAP_DIFFBUS_C0201-DIFF BUS_0A CH4221MEE01              C1571           
Q_CAP_DIFFBUS_C0201-DIFF BUS_0A CH4221MEE01              C1572           
Q_CAP_DIFFBUS_C0201-DIFF BUS_0A CH4221MEE01              C1573           
Q_CAP_DIFFBUS_C0201-DIFF BUS_0A CH4221MEE01              C1574           
Q_CAP_DIFFBUS_C0201-DIFF BUS_0A CH4221MEE01              C1575           
Q_CAP_DIFFBUS_C0201-DIFF BUS_0A CH4221MEE01              C1576           
Q_CAP_DIFFBUS_C0201-DIFF BUS_0A CH4221MEE01              C1577           
Q_CAP_DIFFBUS_C0201-DIFF BUS_0A CH4221MEE01              C1578           
Q_CAP_DIFFBUS_C0201-DIFF BUS_0A CH4221MEE01              C1579           

----------------

Q_CAP_DIFFBUS_C0201-DIFF BUS_0B CH4101KEE02              C1420           
Q_CAP_DIFFBUS_C0201-DIFF BUS_0B CH4101KEE02              C1421           

----------------

Q_CAP_DIFFBUS_C0402-DIFF BUS_0A CH4103K1B08              C643            
Q_CAP_DIFFBUS_C0402-DIFF BUS_0A CH4103K1B08              C644            

----------------

Q_CAP_SATA6G_C0402-SATA6G_0.01A CH31004KB17              C634            
Q_CAP_SATA6G_C0402-SATA6G_0.01A CH31004KB17              C635            
Q_CAP_SATA6G_C0402-SATA6G_0.01A CH31004KB17              C636            
Q_CAP_SATA6G_C0402-SATA6G_0.01A CH31004KB17              C637            

----------------

Q_CRYSTAL_SMLF-32.768KHZ,IC,BGA BG632768012              Y1              

----------------

Q_INDUCTOR4P_12-67/320MA,320MAA CX21SN67000              L5              
Q_INDUCTOR4P_12-67/320MA,320MAA CX21SN67000              L6              
Q_INDUCTOR4P_12-67/320MA,320MAA CX21SN67000              L9              

----------------

Q_INDUCTOR4P_14-150NH,SMLF,INDA CV+15^0TZ04              PL7             
Q_INDUCTOR4P_14-150NH,SMLF,INDA CV+15^0TZ04              PL8             
Q_INDUCTOR4P_14-150NH,SMLF,INDA CV+15^0TZ04              PL9             
Q_INDUCTOR4P_14-150NH,SMLF,INDA CV+15^0TZ04              PL10            
Q_INDUCTOR4P_14-150NH,SMLF,INDA CV+15^0TZ04              PL11            
Q_INDUCTOR4P_14-150NH,SMLF,INDA CV+15^0TZ04              PL13            
Q_INDUCTOR4P_14-150NH,SMLF,INDA CV+15^0TZ04              PL24            
Q_INDUCTOR4P_14-150NH,SMLF,INDA CV+15^0TZ04              PL25            
Q_INDUCTOR4P_14-150NH,SMLF,INDA CV+15^0TZ04              PL26            
Q_INDUCTOR4P_14-150NH,SMLF,INDA CV+15^0TZ04              PL27            
Q_INDUCTOR4P_14-150NH,SMLF,INDA CV+15^0TZ04              PL28            
Q_INDUCTOR4P_14-150NH,SMLF,INDA CV+15^0TZ04              PL29            
Q_INDUCTOR4P_14-150NH,SMLF,INDA CV+15^0TZ04              PL30            
Q_INDUCTOR4P_14-150NH,SMLF,INDA CV+15^0TZ04              PL31            
Q_INDUCTOR4P_14-150NH,SMLF,INDA CV+15^0TZ04              PL112           
Q_INDUCTOR4P_14-150NH,SMLF,INDA CV+15^0TZ04              PL114           

----------------

Q_INDUCTOR_SMLF-1.5UH/53A,IND,A CV-15^0MZ02              PL66            

----------------

Q_INDUCTOR_SMLF-100NH/16A,IND,A CV+10G0MZ04              PL6             
Q_INDUCTOR_SMLF-100NH/16A,IND,A CV+10G0MZ04              PL14            
Q_INDUCTOR_SMLF-100NH/16A,IND,A CV+10G0MZ04              PL23            
Q_INDUCTOR_SMLF-100NH/16A,IND,A CV+10G0MZ04              PL43            
Q_INDUCTOR_SMLF-100NH/16A,IND,A CV+10G0MZ04              PL44            
Q_INDUCTOR_SMLF-100NH/16A,IND,A CV+10G0MZ04              PL45            
Q_INDUCTOR_SMLF-100NH/16A,IND,A CV+10G0MZ04              PL101           
Q_INDUCTOR_SMLF-100NH/16A,IND,A CV+10G0MZ04              PL110           

----------------

Q_INDUCTOR_SMLF-120NH/76A,IND,A CV+12^0TZ06              PL105           
Q_INDUCTOR_SMLF-120NH/76A,IND,A CV+12^0TZ06              PL106           

----------------

Q_INDUCTOR_SMLF-120NH/94A,IND,A CV+12^0KZ16              PL4             
Q_INDUCTOR_SMLF-120NH/94A,IND,A CV+12^0KZ16              PL5             
Q_INDUCTOR_SMLF-120NH/94A,IND,A CV+12^0KZ16              PL17            
Q_INDUCTOR_SMLF-120NH/94A,IND,A CV+12^0KZ16              PL21            
Q_INDUCTOR_SMLF-120NH/94A,IND,A CV+12^0KZ16              PL22            
Q_INDUCTOR_SMLF-120NH/94A,IND,A CV+12^0KZ16              PL35            

----------------

Q_INDUCTOR_SMLF-130NH/106A,EMPA CV+13^0KZ11              PL2             
Q_INDUCTOR_SMLF-130NH/106A,EMPA CV+13^0KZ11              PL210           

----------------

Q_INDUCTOR_SMLF-130NH/106A,INDA CV+13^0KZ11              PL12            
Q_INDUCTOR_SMLF-130NH/106A,INDA CV+13^0KZ11              PL18            
Q_INDUCTOR_SMLF-130NH/106A,INDA CV+13^0KZ11              PL19            
Q_INDUCTOR_SMLF-130NH/106A,INDA CV+13^0KZ11              PL33            
Q_INDUCTOR_SMLF-130NH/106A,INDA CV+13^0KZ11              PL34            
Q_INDUCTOR_SMLF-130NH/106A,INDA CV+13^0KZ11              PL113           

----------------

Q_INDUCTOR_SMLF-1UH,EMPTY,CV-1A CV-10B0MZ13              PL118           

----------------

Q_INDUCTOR_SMLF-1UH,IND,CV-10BA CV-10B0MZ13              PL119           
Q_INDUCTOR_SMLF-1UH,IND,CV-10BA CV-10B0MZ13              PL120           
Q_INDUCTOR_SMLF-1UH,IND,CV-10BA CV-10B0MZ13              PL121           
Q_INDUCTOR_SMLF-1UH,IND,CV-10BA CV-10B0MZ13              PL170           

----------------

Q_INDUCTOR_SMLF-3.3UH/10A,IND,A CV-33A0MZ02              PL65            

----------------

Q_INDUCTOR_SMLF-300NH/33A,IND,A CV+30Y0KZ05              PL3             
Q_INDUCTOR_SMLF-300NH/33A,IND,A CV+30Y0KZ05              PL20            
Q_INDUCTOR_SMLF-300NH/33A,IND,A CV+30Y0KZ05              PL150           

----------------

Q_INDUCTOR_SMLF-50NH/148A,IND,A CVA50^0EZ01              PL15            
Q_INDUCTOR_SMLF-50NH/148A,IND,A CVA50^0EZ01              PL32            

----------------

Q_INDUCTOR_SMLF-BLM15AG121SN1DA CX5AG121002              L11             
Q_INDUCTOR_SMLF-BLM15AG121SN1DA CX5AG121002              L12             

----------------

Q_INDUCTOR_SMLF-BLM18PG121SN1DA CX8PG121009              L2              
Q_INDUCTOR_SMLF-BLM18PG121SN1DA CX8PG121009              L10             
Q_INDUCTOR_SMLF-BLM18PG121SN1DA CX8PG121009              L36             

----------------

Q_INDUCTOR_SMLF-BLM18SG331TN1DA CX8SG331000              L3              
Q_INDUCTOR_SMLF-BLM18SG331TN1DA CX8SG331000              L4              

----------------

Q_INDUCTOR_SMLF-BLM18SN220TN1DA CX220TN1001              PL16            
Q_INDUCTOR_SMLF-BLM18SN220TN1DA CX220TN1001              PL64            

----------------

Q_INDUCTOR_SMLF-FCM2012KF-601TA CX601T05003              L1              
Q_INDUCTOR_SMLF-FCM2012KF-601TA CX601T05003              L13             
Q_INDUCTOR_SMLF-FCM2012KF-601TA CX601T05003              L14             

----------------

Q_LED_SMLF-LED_GREEN,19-213/GVA BEGR0278Z00              D0              

----------------

Q_LED_SMLF-LED_RED,19-217/R6C-A BERD0034Z07              D6              

----------------

Q_OSC4P_SMLF-25MHZ,OSC,BF62500A BF625000014              OSC2            

----------------

Q_RES_0402LF -9.53K,1%,1/16W ,A CS29532FB10              PR259           

----------------

Q_RES_0402LF-0,1%,1/16W,CHIP,TA CS00002FB00              R1786           
Q_RES_0402LF-0,1%,1/16W,CHIP,TA CS00002FB00              R1788           

----------------

Q_RES_0402LF-0,5%,1/16W,CHIP,CA CS00002JB38              PR108           
Q_RES_0402LF-0,5%,1/16W,CHIP,CA CS00002JB38              PR110           
Q_RES_0402LF-0,5%,1/16W,CHIP,CA CS00002JB38              PR111           
Q_RES_0402LF-0,5%,1/16W,CHIP,CA CS00002JB38              PR113           
Q_RES_0402LF-0,5%,1/16W,CHIP,CA CS00002JB38              PR114           
Q_RES_0402LF-0,5%,1/16W,CHIP,CA CS00002JB38              PR115           
Q_RES_0402LF-0,5%,1/16W,CHIP,CA CS00002JB38              PR116           
Q_RES_0402LF-0,5%,1/16W,CHIP,CA CS00002JB38              PR118           
Q_RES_0402LF-0,5%,1/16W,CHIP,CA CS00002JB38              PR119           
Q_RES_0402LF-0,5%,1/16W,CHIP,CA CS00002JB38              PR120           
Q_RES_0402LF-0,5%,1/16W,CHIP,CA CS00002JB38              PR121           
Q_RES_0402LF-0,5%,1/16W,CHIP,CA CS00002JB38              PR122           
Q_RES_0402LF-0,5%,1/16W,CHIP,CA CS00002JB38              PR136           
Q_RES_0402LF-0,5%,1/16W,CHIP,CA CS00002JB38              PR137           
Q_RES_0402LF-0,5%,1/16W,CHIP,CA CS00002JB38              PR142           
Q_RES_0402LF-0,5%,1/16W,CHIP,CA CS00002JB38              PR143           
Q_RES_0402LF-0,5%,1/16W,CHIP,CA CS00002JB38              PR148           
Q_RES_0402LF-0,5%,1/16W,CHIP,CA CS00002JB38              PR149           
Q_RES_0402LF-0,5%,1/16W,CHIP,CA CS00002JB38              PR154           
Q_RES_0402LF-0,5%,1/16W,CHIP,CA CS00002JB38              PR155           
Q_RES_0402LF-0,5%,1/16W,CHIP,CA CS00002JB38              PR156           
Q_RES_0402LF-0,5%,1/16W,CHIP,CA CS00002JB38              PR158           
Q_RES_0402LF-0,5%,1/16W,CHIP,CA CS00002JB38              PR161           
Q_RES_0402LF-0,5%,1/16W,CHIP,CA CS00002JB38              PR162           
Q_RES_0402LF-0,5%,1/16W,CHIP,CA CS00002JB38              PR164           
Q_RES_0402LF-0,5%,1/16W,CHIP,CA CS00002JB38              PR165           
Q_RES_0402LF-0,5%,1/16W,CHIP,CA CS00002JB38              PR167           
Q_RES_0402LF-0,5%,1/16W,CHIP,CA CS00002JB38              PR168           
Q_RES_0402LF-0,5%,1/16W,CHIP,CA CS00002JB38              PR170           
Q_RES_0402LF-0,5%,1/16W,CHIP,CA CS00002JB38              PR171           
Q_RES_0402LF-0,5%,1/16W,CHIP,CA CS00002JB38              PR207           
Q_RES_0402LF-0,5%,1/16W,CHIP,CA CS00002JB38              PR208           
Q_RES_0402LF-0,5%,1/16W,CHIP,CA CS00002JB38              PR210           
Q_RES_0402LF-0,5%,1/16W,CHIP,CA CS00002JB38              PR211           
Q_RES_0402LF-0,5%,1/16W,CHIP,CA CS00002JB38              PR212           
Q_RES_0402LF-0,5%,1/16W,CHIP,CA CS00002JB38              PR213           
Q_RES_0402LF-0,5%,1/16W,CHIP,CA CS00002JB38              PR216           
Q_RES_0402LF-0,5%,1/16W,CHIP,CA CS00002JB38              PR233           
Q_RES_0402LF-0,5%,1/16W,CHIP,CA CS00002JB38              PR234           
Q_RES_0402LF-0,5%,1/16W,CHIP,CA CS00002JB38              PR242           
Q_RES_0402LF-0,5%,1/16W,CHIP,CA CS00002JB38              PR261           
Q_RES_0402LF-0,5%,1/16W,CHIP,CA CS00002JB38              PR263           
Q_RES_0402LF-0,5%,1/16W,CHIP,CA CS00002JB38              PR264           
Q_RES_0402LF-0,5%,1/16W,CHIP,CA CS00002JB38              PR266           
Q_RES_0402LF-0,5%,1/16W,CHIP,CA CS00002JB38              PR267           
Q_RES_0402LF-0,5%,1/16W,CHIP,CA CS00002JB38              PR268           
Q_RES_0402LF-0,5%,1/16W,CHIP,CA CS00002JB38              PR269           
Q_RES_0402LF-0,5%,1/16W,CHIP,CA CS00002JB38              PR271           
Q_RES_0402LF-0,5%,1/16W,CHIP,CA CS00002JB38              PR272           
Q_RES_0402LF-0,5%,1/16W,CHIP,CA CS00002JB38              PR273           
Q_RES_0402LF-0,5%,1/16W,CHIP,CA CS00002JB38              PR274           
Q_RES_0402LF-0,5%,1/16W,CHIP,CA CS00002JB38              PR275           
Q_RES_0402LF-0,5%,1/16W,CHIP,CA CS00002JB38              PR289           
Q_RES_0402LF-0,5%,1/16W,CHIP,CA CS00002JB38              PR290           
Q_RES_0402LF-0,5%,1/16W,CHIP,CA CS00002JB38              PR295           
Q_RES_0402LF-0,5%,1/16W,CHIP,CA CS00002JB38              PR296           
Q_RES_0402LF-0,5%,1/16W,CHIP,CA CS00002JB38              PR301           
Q_RES_0402LF-0,5%,1/16W,CHIP,CA CS00002JB38              PR302           
Q_RES_0402LF-0,5%,1/16W,CHIP,CA CS00002JB38              PR303           
Q_RES_0402LF-0,5%,1/16W,CHIP,CA CS00002JB38              PR305           
Q_RES_0402LF-0,5%,1/16W,CHIP,CA CS00002JB38              PR308           
Q_RES_0402LF-0,5%,1/16W,CHIP,CA CS00002JB38              PR309           
Q_RES_0402LF-0,5%,1/16W,CHIP,CA CS00002JB38              PR311           
Q_RES_0402LF-0,5%,1/16W,CHIP,CA CS00002JB38              PR312           
Q_RES_0402LF-0,5%,1/16W,CHIP,CA CS00002JB38              PR314           
Q_RES_0402LF-0,5%,1/16W,CHIP,CA CS00002JB38              PR315           
Q_RES_0402LF-0,5%,1/16W,CHIP,CA CS00002JB38              PR317           
Q_RES_0402LF-0,5%,1/16W,CHIP,CA CS00002JB38              PR329           
Q_RES_0402LF-0,5%,1/16W,CHIP,CA CS00002JB38              PR330           
Q_RES_0402LF-0,5%,1/16W,CHIP,CA CS00002JB38              PR336           
Q_RES_0402LF-0,5%,1/16W,CHIP,CA CS00002JB38              PR337           
Q_RES_0402LF-0,5%,1/16W,CHIP,CA CS00002JB38              PR345           
Q_RES_0402LF-0,5%,1/16W,CHIP,CA CS00002JB38              PR362           
Q_RES_0402LF-0,5%,1/16W,CHIP,CA CS00002JB38              PR363           
Q_RES_0402LF-0,5%,1/16W,CHIP,CA CS00002JB38              PR365           
Q_RES_0402LF-0,5%,1/16W,CHIP,CA CS00002JB38              PR366           
Q_RES_0402LF-0,5%,1/16W,CHIP,CA CS00002JB38              PR367           
Q_RES_0402LF-0,5%,1/16W,CHIP,CA CS00002JB38              PR368           
Q_RES_0402LF-0,5%,1/16W,CHIP,CA CS00002JB38              PR371           
Q_RES_0402LF-0,5%,1/16W,CHIP,CA CS00002JB38              PR395           
Q_RES_0402LF-0,5%,1/16W,CHIP,CA CS00002JB38              PR402           
Q_RES_0402LF-0,5%,1/16W,CHIP,CA CS00002JB38              PR411           
Q_RES_0402LF-0,5%,1/16W,CHIP,CA CS00002JB38              PR437           
Q_RES_0402LF-0,5%,1/16W,CHIP,CA CS00002JB38              PR442           
Q_RES_0402LF-0,5%,1/16W,CHIP,CA CS00002JB38              PR444           
Q_RES_0402LF-0,5%,1/16W,CHIP,CA CS00002JB38              PR447           
Q_RES_0402LF-0,5%,1/16W,CHIP,CA CS00002JB38              PR451           
Q_RES_0402LF-0,5%,1/16W,CHIP,CA CS00002JB38              PR453           
Q_RES_0402LF-0,5%,1/16W,CHIP,CA CS00002JB38              PR635           
Q_RES_0402LF-0,5%,1/16W,CHIP,CA CS00002JB38              PR639           
Q_RES_0402LF-0,5%,1/16W,CHIP,CA CS00002JB38              PR668           
Q_RES_0402LF-0,5%,1/16W,CHIP,CA CS00002JB38              PR678           
Q_RES_0402LF-0,5%,1/16W,CHIP,CA CS00002JB38              PR701           
Q_RES_0402LF-0,5%,1/16W,CHIP,CA CS00002JB38              PR702           
Q_RES_0402LF-0,5%,1/16W,CHIP,CA CS00002JB38              PR706           
Q_RES_0402LF-0,5%,1/16W,CHIP,CA CS00002JB38              PR835           
Q_RES_0402LF-0,5%,1/16W,CHIP,CA CS00002JB38              PR1311          
Q_RES_0402LF-0,5%,1/16W,CHIP,CA CS00002JB38              PR1315          
Q_RES_0402LF-0,5%,1/16W,CHIP,CA CS00002JB38              PR1322          
Q_RES_0402LF-0,5%,1/16W,CHIP,CA CS00002JB38              PR1323          
Q_RES_0402LF-0,5%,1/16W,CHIP,CA CS00002JB38              PR1326          
Q_RES_0402LF-0,5%,1/16W,CHIP,CA CS00002JB38              PR1331          
Q_RES_0402LF-0,5%,1/16W,CHIP,CA CS00002JB38              PR1332          
Q_RES_0402LF-0,5%,1/16W,CHIP,CA CS00002JB38              PR1333          
Q_RES_0402LF-0,5%,1/16W,CHIP,CA CS00002JB38              PR1334          
Q_RES_0402LF-0,5%,1/16W,CHIP,CA CS00002JB38              PR1338          
Q_RES_0402LF-0,5%,1/16W,CHIP,CA CS00002JB38              PR1389          
Q_RES_0402LF-0,5%,1/16W,CHIP,CA CS00002JB38              PR1650          
Q_RES_0402LF-0,5%,1/16W,CHIP,CA CS00002JB38              PR1651          
Q_RES_0402LF-0,5%,1/16W,CHIP,CA CS00002JB38              PR1776          
Q_RES_0402LF-0,5%,1/16W,CHIP,CA CS00002JB38              PR1777          
Q_RES_0402LF-0,5%,1/16W,CHIP,CA CS00002JB38              PR1779          
Q_RES_0402LF-0,5%,1/16W,CHIP,CA CS00002JB38              PR1785          
Q_RES_0402LF-0,5%,1/16W,CHIP,CA CS00002JB38              PR1796          
Q_RES_0402LF-0,5%,1/16W,CHIP,CA CS00002JB38              PR1797          
Q_RES_0402LF-0,5%,1/16W,CHIP,CA CS00002JB38              PR1799          
Q_RES_0402LF-0,5%,1/16W,CHIP,CA CS00002JB38              PR1805          
Q_RES_0402LF-0,5%,1/16W,CHIP,CA CS00002JB38              PR2390          
Q_RES_0402LF-0,5%,1/16W,CHIP,CA CS00002JB38              R12             
Q_RES_0402LF-0,5%,1/16W,CHIP,CA CS00002JB38              R13             
Q_RES_0402LF-0,5%,1/16W,CHIP,CA CS00002JB38              R15             
Q_RES_0402LF-0,5%,1/16W,CHIP,CA CS00002JB38              R16             
Q_RES_0402LF-0,5%,1/16W,CHIP,CA CS00002JB38              R20             
Q_RES_0402LF-0,5%,1/16W,CHIP,CA CS00002JB38              R21             
Q_RES_0402LF-0,5%,1/16W,CHIP,CA CS00002JB38              R55             
Q_RES_0402LF-0,5%,1/16W,CHIP,CA CS00002JB38              R56             
Q_RES_0402LF-0,5%,1/16W,CHIP,CA CS00002JB38              R58             
Q_RES_0402LF-0,5%,1/16W,CHIP,CA CS00002JB38              R59             
Q_RES_0402LF-0,5%,1/16W,CHIP,CA CS00002JB38              R107            
Q_RES_0402LF-0,5%,1/16W,CHIP,CA CS00002JB38              R122            
Q_RES_0402LF-0,5%,1/16W,CHIP,CA CS00002JB38              R124            
Q_RES_0402LF-0,5%,1/16W,CHIP,CA CS00002JB38              R126            
Q_RES_0402LF-0,5%,1/16W,CHIP,CA CS00002JB38              R128            
Q_RES_0402LF-0,5%,1/16W,CHIP,CA CS00002JB38              R130            
Q_RES_0402LF-0,5%,1/16W,CHIP,CA CS00002JB38              R132            
Q_RES_0402LF-0,5%,1/16W,CHIP,CA CS00002JB38              R142            
Q_RES_0402LF-0,5%,1/16W,CHIP,CA CS00002JB38              R160            
Q_RES_0402LF-0,5%,1/16W,CHIP,CA CS00002JB38              R162            
Q_RES_0402LF-0,5%,1/16W,CHIP,CA CS00002JB38              R164            
Q_RES_0402LF-0,5%,1/16W,CHIP,CA CS00002JB38              R166            
Q_RES_0402LF-0,5%,1/16W,CHIP,CA CS00002JB38              R168            
Q_RES_0402LF-0,5%,1/16W,CHIP,CA CS00002JB38              R171            
Q_RES_0402LF-0,5%,1/16W,CHIP,CA CS00002JB38              R188            
Q_RES_0402LF-0,5%,1/16W,CHIP,CA CS00002JB38              R208            
Q_RES_0402LF-0,5%,1/16W,CHIP,CA CS00002JB38              R210            
Q_RES_0402LF-0,5%,1/16W,CHIP,CA CS00002JB38              R237            
Q_RES_0402LF-0,5%,1/16W,CHIP,CA CS00002JB38              R238            
Q_RES_0402LF-0,5%,1/16W,CHIP,CA CS00002JB38              R239            
Q_RES_0402LF-0,5%,1/16W,CHIP,CA CS00002JB38              R240            
Q_RES_0402LF-0,5%,1/16W,CHIP,CA CS00002JB38              R297            
Q_RES_0402LF-0,5%,1/16W,CHIP,CA CS00002JB38              R299            
Q_RES_0402LF-0,5%,1/16W,CHIP,CA CS00002JB38              R336            
Q_RES_0402LF-0,5%,1/16W,CHIP,CA CS00002JB38              R337            
Q_RES_0402LF-0,5%,1/16W,CHIP,CA CS00002JB38              R340            
Q_RES_0402LF-0,5%,1/16W,CHIP,CA CS00002JB38              R341            
Q_RES_0402LF-0,5%,1/16W,CHIP,CA CS00002JB38              R344            
Q_RES_0402LF-0,5%,1/16W,CHIP,CA CS00002JB38              R345            
Q_RES_0402LF-0,5%,1/16W,CHIP,CA CS00002JB38              R365            
Q_RES_0402LF-0,5%,1/16W,CHIP,CA CS00002JB38              R416            
Q_RES_0402LF-0,5%,1/16W,CHIP,CA CS00002JB38              R417            
Q_RES_0402LF-0,5%,1/16W,CHIP,CA CS00002JB38              R418            
Q_RES_0402LF-0,5%,1/16W,CHIP,CA CS00002JB38              R429            
Q_RES_0402LF-0,5%,1/16W,CHIP,CA CS00002JB38              R444            
Q_RES_0402LF-0,5%,1/16W,CHIP,CA CS00002JB38              R445            
Q_RES_0402LF-0,5%,1/16W,CHIP,CA CS00002JB38              R464            
Q_RES_0402LF-0,5%,1/16W,CHIP,CA CS00002JB38              R465            
Q_RES_0402LF-0,5%,1/16W,CHIP,CA CS00002JB38              R466            
Q_RES_0402LF-0,5%,1/16W,CHIP,CA CS00002JB38              R468            
Q_RES_0402LF-0,5%,1/16W,CHIP,CA CS00002JB38              R469            
Q_RES_0402LF-0,5%,1/16W,CHIP,CA CS00002JB38              R470            
Q_RES_0402LF-0,5%,1/16W,CHIP,CA CS00002JB38              R471            
Q_RES_0402LF-0,5%,1/16W,CHIP,CA CS00002JB38              R473            
Q_RES_0402LF-0,5%,1/16W,CHIP,CA CS00002JB38              R480            
Q_RES_0402LF-0,5%,1/16W,CHIP,CA CS00002JB38              R481            
Q_RES_0402LF-0,5%,1/16W,CHIP,CA CS00002JB38              R482            
Q_RES_0402LF-0,5%,1/16W,CHIP,CA CS00002JB38              R483            
Q_RES_0402LF-0,5%,1/16W,CHIP,CA CS00002JB38              R485            
Q_RES_0402LF-0,5%,1/16W,CHIP,CA CS00002JB38              R486            
Q_RES_0402LF-0,5%,1/16W,CHIP,CA CS00002JB38              R506            
Q_RES_0402LF-0,5%,1/16W,CHIP,CA CS00002JB38              R509            
Q_RES_0402LF-0,5%,1/16W,CHIP,CA CS00002JB38              R520            
Q_RES_0402LF-0,5%,1/16W,CHIP,CA CS00002JB38              R521            
Q_RES_0402LF-0,5%,1/16W,CHIP,CA CS00002JB38              R522            
Q_RES_0402LF-0,5%,1/16W,CHIP,CA CS00002JB38              R523            
Q_RES_0402LF-0,5%,1/16W,CHIP,CA CS00002JB38              R524            
Q_RES_0402LF-0,5%,1/16W,CHIP,CA CS00002JB38              R525            
Q_RES_0402LF-0,5%,1/16W,CHIP,CA CS00002JB38              R526            
Q_RES_0402LF-0,5%,1/16W,CHIP,CA CS00002JB38              R527            
Q_RES_0402LF-0,5%,1/16W,CHIP,CA CS00002JB38              R528            
Q_RES_0402LF-0,5%,1/16W,CHIP,CA CS00002JB38              R529            
Q_RES_0402LF-0,5%,1/16W,CHIP,CA CS00002JB38              R530            
Q_RES_0402LF-0,5%,1/16W,CHIP,CA CS00002JB38              R531            
Q_RES_0402LF-0,5%,1/16W,CHIP,CA CS00002JB38              R532            
Q_RES_0402LF-0,5%,1/16W,CHIP,CA CS00002JB38              R533            
Q_RES_0402LF-0,5%,1/16W,CHIP,CA CS00002JB38              R534            
Q_RES_0402LF-0,5%,1/16W,CHIP,CA CS00002JB38              R535            
Q_RES_0402LF-0,5%,1/16W,CHIP,CA CS00002JB38              R541            
Q_RES_0402LF-0,5%,1/16W,CHIP,CA CS00002JB38              R553            
Q_RES_0402LF-0,5%,1/16W,CHIP,CA CS00002JB38              R554            
Q_RES_0402LF-0,5%,1/16W,CHIP,CA CS00002JB38              R563            
Q_RES_0402LF-0,5%,1/16W,CHIP,CA CS00002JB38              R564            
Q_RES_0402LF-0,5%,1/16W,CHIP,CA CS00002JB38              R565            
Q_RES_0402LF-0,5%,1/16W,CHIP,CA CS00002JB38              R566            
Q_RES_0402LF-0,5%,1/16W,CHIP,CA CS00002JB38              R593            
Q_RES_0402LF-0,5%,1/16W,CHIP,CA CS00002JB38              R594            
Q_RES_0402LF-0,5%,1/16W,CHIP,CA CS00002JB38              R595            
Q_RES_0402LF-0,5%,1/16W,CHIP,CA CS00002JB38              R596            
Q_RES_0402LF-0,5%,1/16W,CHIP,CA CS00002JB38              R597            
Q_RES_0402LF-0,5%,1/16W,CHIP,CA CS00002JB38              R598            
Q_RES_0402LF-0,5%,1/16W,CHIP,CA CS00002JB38              R599            
Q_RES_0402LF-0,5%,1/16W,CHIP,CA CS00002JB38              R600            
Q_RES_0402LF-0,5%,1/16W,CHIP,CA CS00002JB38              R648            
Q_RES_0402LF-0,5%,1/16W,CHIP,CA CS00002JB38              R659            
Q_RES_0402LF-0,5%,1/16W,CHIP,CA CS00002JB38              R660            
Q_RES_0402LF-0,5%,1/16W,CHIP,CA CS00002JB38              R674            
Q_RES_0402LF-0,5%,1/16W,CHIP,CA CS00002JB38              R675            
Q_RES_0402LF-0,5%,1/16W,CHIP,CA CS00002JB38              R676            
Q_RES_0402LF-0,5%,1/16W,CHIP,CA CS00002JB38              R677            
Q_RES_0402LF-0,5%,1/16W,CHIP,CA CS00002JB38              R691            
Q_RES_0402LF-0,5%,1/16W,CHIP,CA CS00002JB38              R692            
Q_RES_0402LF-0,5%,1/16W,CHIP,CA CS00002JB38              R693            
Q_RES_0402LF-0,5%,1/16W,CHIP,CA CS00002JB38              R694            
Q_RES_0402LF-0,5%,1/16W,CHIP,CA CS00002JB38              R700            
Q_RES_0402LF-0,5%,1/16W,CHIP,CA CS00002JB38              R737            
Q_RES_0402LF-0,5%,1/16W,CHIP,CA CS00002JB38              R738            
Q_RES_0402LF-0,5%,1/16W,CHIP,CA CS00002JB38              R746            
Q_RES_0402LF-0,5%,1/16W,CHIP,CA CS00002JB38              R762            
Q_RES_0402LF-0,5%,1/16W,CHIP,CA CS00002JB38              R764            
Q_RES_0402LF-0,5%,1/16W,CHIP,CA CS00002JB38              R765            
Q_RES_0402LF-0,5%,1/16W,CHIP,CA CS00002JB38              R787            
Q_RES_0402LF-0,5%,1/16W,CHIP,CA CS00002JB38              R788            
Q_RES_0402LF-0,5%,1/16W,CHIP,CA CS00002JB38              R789            
Q_RES_0402LF-0,5%,1/16W,CHIP,CA CS00002JB38              R790            
Q_RES_0402LF-0,5%,1/16W,CHIP,CA CS00002JB38              R799            
Q_RES_0402LF-0,5%,1/16W,CHIP,CA CS00002JB38              R800            
Q_RES_0402LF-0,5%,1/16W,CHIP,CA CS00002JB38              R801            
Q_RES_0402LF-0,5%,1/16W,CHIP,CA CS00002JB38              R802            
Q_RES_0402LF-0,5%,1/16W,CHIP,CA CS00002JB38              R815            
Q_RES_0402LF-0,5%,1/16W,CHIP,CA CS00002JB38              R816            
Q_RES_0402LF-0,5%,1/16W,CHIP,CA CS00002JB38              R817            
Q_RES_0402LF-0,5%,1/16W,CHIP,CA CS00002JB38              R818            
Q_RES_0402LF-0,5%,1/16W,CHIP,CA CS00002JB38              R835            
Q_RES_0402LF-0,5%,1/16W,CHIP,CA CS00002JB38              R836            
Q_RES_0402LF-0,5%,1/16W,CHIP,CA CS00002JB38              R837            
Q_RES_0402LF-0,5%,1/16W,CHIP,CA CS00002JB38              R838            
Q_RES_0402LF-0,5%,1/16W,CHIP,CA CS00002JB38              R851            
Q_RES_0402LF-0,5%,1/16W,CHIP,CA CS00002JB38              R852            
Q_RES_0402LF-0,5%,1/16W,CHIP,CA CS00002JB38              R853            
Q_RES_0402LF-0,5%,1/16W,CHIP,CA CS00002JB38              R854            
Q_RES_0402LF-0,5%,1/16W,CHIP,CA CS00002JB38              R859            
Q_RES_0402LF-0,5%,1/16W,CHIP,CA CS00002JB38              R860            
Q_RES_0402LF-0,5%,1/16W,CHIP,CA CS00002JB38              R861            
Q_RES_0402LF-0,5%,1/16W,CHIP,CA CS00002JB38              R862            
Q_RES_0402LF-0,5%,1/16W,CHIP,CA CS00002JB38              R931            
Q_RES_0402LF-0,5%,1/16W,CHIP,CA CS00002JB38              R948            
Q_RES_0402LF-0,5%,1/16W,CHIP,CA CS00002JB38              R951            
Q_RES_0402LF-0,5%,1/16W,CHIP,CA CS00002JB38              R998            
Q_RES_0402LF-0,5%,1/16W,CHIP,CA CS00002JB38              R999            
Q_RES_0402LF-0,5%,1/16W,CHIP,CA CS00002JB38              R1010           
Q_RES_0402LF-0,5%,1/16W,CHIP,CA CS00002JB38              R1011           
Q_RES_0402LF-0,5%,1/16W,CHIP,CA CS00002JB38              R1012           
Q_RES_0402LF-0,5%,1/16W,CHIP,CA CS00002JB38              R1014           
Q_RES_0402LF-0,5%,1/16W,CHIP,CA CS00002JB38              R1016           
Q_RES_0402LF-0,5%,1/16W,CHIP,CA CS00002JB38              R1018           
Q_RES_0402LF-0,5%,1/16W,CHIP,CA CS00002JB38              R1020           
Q_RES_0402LF-0,5%,1/16W,CHIP,CA CS00002JB38              R1021           
Q_RES_0402LF-0,5%,1/16W,CHIP,CA CS00002JB38              R1022           
Q_RES_0402LF-0,5%,1/16W,CHIP,CA CS00002JB38              R1023           
Q_RES_0402LF-0,5%,1/16W,CHIP,CA CS00002JB38              R1051           
Q_RES_0402LF-0,5%,1/16W,CHIP,CA CS00002JB38              R1052           
Q_RES_0402LF-0,5%,1/16W,CHIP,CA CS00002JB38              R1053           
Q_RES_0402LF-0,5%,1/16W,CHIP,CA CS00002JB38              R1054           
Q_RES_0402LF-0,5%,1/16W,CHIP,CA CS00002JB38              R1055           
Q_RES_0402LF-0,5%,1/16W,CHIP,CA CS00002JB38              R1056           
Q_RES_0402LF-0,5%,1/16W,CHIP,CA CS00002JB38              R1058           
Q_RES_0402LF-0,5%,1/16W,CHIP,CA CS00002JB38              R1059           
Q_RES_0402LF-0,5%,1/16W,CHIP,CA CS00002JB38              R1060           
Q_RES_0402LF-0,5%,1/16W,CHIP,CA CS00002JB38              R1061           
Q_RES_0402LF-0,5%,1/16W,CHIP,CA CS00002JB38              R1062           
Q_RES_0402LF-0,5%,1/16W,CHIP,CA CS00002JB38              R1063           
Q_RES_0402LF-0,5%,1/16W,CHIP,CA CS00002JB38              R1064           
Q_RES_0402LF-0,5%,1/16W,CHIP,CA CS00002JB38              R1134           
Q_RES_0402LF-0,5%,1/16W,CHIP,CA CS00002JB38              R1136           
Q_RES_0402LF-0,5%,1/16W,CHIP,CA CS00002JB38              R1139           
Q_RES_0402LF-0,5%,1/16W,CHIP,CA CS00002JB38              R1147           
Q_RES_0402LF-0,5%,1/16W,CHIP,CA CS00002JB38              R1148           
Q_RES_0402LF-0,5%,1/16W,CHIP,CA CS00002JB38              R1184           
Q_RES_0402LF-0,5%,1/16W,CHIP,CA CS00002JB38              R1214           
Q_RES_0402LF-0,5%,1/16W,CHIP,CA CS00002JB38              R1240           
Q_RES_0402LF-0,5%,1/16W,CHIP,CA CS00002JB38              R1245           
Q_RES_0402LF-0,5%,1/16W,CHIP,CA CS00002JB38              R1247           
Q_RES_0402LF-0,5%,1/16W,CHIP,CA CS00002JB38              R1249           
Q_RES_0402LF-0,5%,1/16W,CHIP,CA CS00002JB38              R1273           
Q_RES_0402LF-0,5%,1/16W,CHIP,CA CS00002JB38              R1274           
Q_RES_0402LF-0,5%,1/16W,CHIP,CA CS00002JB38              R1275           
Q_RES_0402LF-0,5%,1/16W,CHIP,CA CS00002JB38              R1276           
Q_RES_0402LF-0,5%,1/16W,CHIP,CA CS00002JB38              R1277           
Q_RES_0402LF-0,5%,1/16W,CHIP,CA CS00002JB38              R1278           
Q_RES_0402LF-0,5%,1/16W,CHIP,CA CS00002JB38              R1279           
Q_RES_0402LF-0,5%,1/16W,CHIP,CA CS00002JB38              R1280           
Q_RES_0402LF-0,5%,1/16W,CHIP,CA CS00002JB38              R1281           
Q_RES_0402LF-0,5%,1/16W,CHIP,CA CS00002JB38              R1282           
Q_RES_0402LF-0,5%,1/16W,CHIP,CA CS00002JB38              R1283           
Q_RES_0402LF-0,5%,1/16W,CHIP,CA CS00002JB38              R1284           
Q_RES_0402LF-0,5%,1/16W,CHIP,CA CS00002JB38              R1345           
Q_RES_0402LF-0,5%,1/16W,CHIP,CA CS00002JB38              R1348           
Q_RES_0402LF-0,5%,1/16W,CHIP,CA CS00002JB38              R1349           
Q_RES_0402LF-0,5%,1/16W,CHIP,CA CS00002JB38              R1361           
Q_RES_0402LF-0,5%,1/16W,CHIP,CA CS00002JB38              R1362           
Q_RES_0402LF-0,5%,1/16W,CHIP,CA CS00002JB38              R1363           
Q_RES_0402LF-0,5%,1/16W,CHIP,CA CS00002JB38              R1364           
Q_RES_0402LF-0,5%,1/16W,CHIP,CA CS00002JB38              R1461           
Q_RES_0402LF-0,5%,1/16W,CHIP,CA CS00002JB38              R1463           
Q_RES_0402LF-0,5%,1/16W,CHIP,CA CS00002JB38              R1464           
Q_RES_0402LF-0,5%,1/16W,CHIP,CA CS00002JB38              R1525           
Q_RES_0402LF-0,5%,1/16W,CHIP,CA CS00002JB38              R1543           
Q_RES_0402LF-0,5%,1/16W,CHIP,CA CS00002JB38              R1544           
Q_RES_0402LF-0,5%,1/16W,CHIP,CA CS00002JB38              R1547           
Q_RES_0402LF-0,5%,1/16W,CHIP,CA CS00002JB38              R1573           
Q_RES_0402LF-0,5%,1/16W,CHIP,CA CS00002JB38              R1577           
Q_RES_0402LF-0,5%,1/16W,CHIP,CA CS00002JB38              R1585           
Q_RES_0402LF-0,5%,1/16W,CHIP,CA CS00002JB38              R1587           
Q_RES_0402LF-0,5%,1/16W,CHIP,CA CS00002JB38              R1589           
Q_RES_0402LF-0,5%,1/16W,CHIP,CA CS00002JB38              R1606           
Q_RES_0402LF-0,5%,1/16W,CHIP,CA CS00002JB38              R1607           
Q_RES_0402LF-0,5%,1/16W,CHIP,CA CS00002JB38              R1652           
Q_RES_0402LF-0,5%,1/16W,CHIP,CA CS00002JB38              R1671           
Q_RES_0402LF-0,5%,1/16W,CHIP,CA CS00002JB38              R1680           
Q_RES_0402LF-0,5%,1/16W,CHIP,CA CS00002JB38              R1721           
Q_RES_0402LF-0,5%,1/16W,CHIP,CA CS00002JB38              R1724           
Q_RES_0402LF-0,5%,1/16W,CHIP,CA CS00002JB38              R1736           
Q_RES_0402LF-0,5%,1/16W,CHIP,CA CS00002JB38              R1744           
Q_RES_0402LF-0,5%,1/16W,CHIP,CA CS00002JB38              R1748           
Q_RES_0402LF-0,5%,1/16W,CHIP,CA CS00002JB38              R1792           
Q_RES_0402LF-0,5%,1/16W,CHIP,CA CS00002JB38              R1793           
Q_RES_0402LF-0,5%,1/16W,CHIP,CA CS00002JB38              R1798           
Q_RES_0402LF-0,5%,1/16W,CHIP,CA CS00002JB38              R1801           
Q_RES_0402LF-0,5%,1/16W,CHIP,CA CS00002JB38              R1815           
Q_RES_0402LF-0,5%,1/16W,CHIP,CA CS00002JB38              R1816           
Q_RES_0402LF-0,5%,1/16W,CHIP,CA CS00002JB38              R1833           
Q_RES_0402LF-0,5%,1/16W,CHIP,CA CS00002JB38              R1836           
Q_RES_0402LF-0,5%,1/16W,CHIP,CA CS00002JB38              R1845           
Q_RES_0402LF-0,5%,1/16W,CHIP,CA CS00002JB38              R1853           
Q_RES_0402LF-0,5%,1/16W,CHIP,CA CS00002JB38              R1868           
Q_RES_0402LF-0,5%,1/16W,CHIP,CA CS00002JB38              R1869           
Q_RES_0402LF-0,5%,1/16W,CHIP,CA CS00002JB38              R1870           
Q_RES_0402LF-0,5%,1/16W,CHIP,CA CS00002JB38              R1871           
Q_RES_0402LF-0,5%,1/16W,CHIP,CA CS00002JB38              R1872           
Q_RES_0402LF-0,5%,1/16W,CHIP,CA CS00002JB38              R1925           
Q_RES_0402LF-0,5%,1/16W,CHIP,CA CS00002JB38              R1944           
Q_RES_0402LF-0,5%,1/16W,CHIP,CA CS00002JB38              R1950           
Q_RES_0402LF-0,5%,1/16W,CHIP,CA CS00002JB38              R1959           
Q_RES_0402LF-0,5%,1/16W,CHIP,CA CS00002JB38              R1960           
Q_RES_0402LF-0,5%,1/16W,CHIP,CA CS00002JB38              R1965           
Q_RES_0402LF-0,5%,1/16W,CHIP,CA CS00002JB38              R1975           
Q_RES_0402LF-0,5%,1/16W,CHIP,CA CS00002JB38              R1985           
Q_RES_0402LF-0,5%,1/16W,CHIP,CA CS00002JB38              R2048           
Q_RES_0402LF-0,5%,1/16W,CHIP,CA CS00002JB38              R2049           
Q_RES_0402LF-0,5%,1/16W,CHIP,CA CS00002JB38              R2059           
Q_RES_0402LF-0,5%,1/16W,CHIP,CA CS00002JB38              R2060           
Q_RES_0402LF-0,5%,1/16W,CHIP,CA CS00002JB38              R2061           
Q_RES_0402LF-0,5%,1/16W,CHIP,CA CS00002JB38              R2062           
Q_RES_0402LF-0,5%,1/16W,CHIP,CA CS00002JB38              R2063           
Q_RES_0402LF-0,5%,1/16W,CHIP,CA CS00002JB38              R2064           
Q_RES_0402LF-0,5%,1/16W,CHIP,CA CS00002JB38              R2065           
Q_RES_0402LF-0,5%,1/16W,CHIP,CA CS00002JB38              R2066           
Q_RES_0402LF-0,5%,1/16W,CHIP,CA CS00002JB38              R2070           
Q_RES_0402LF-0,5%,1/16W,CHIP,CA CS00002JB38              R2074           
Q_RES_0402LF-0,5%,1/16W,CHIP,CA CS00002JB38              R2086           
Q_RES_0402LF-0,5%,1/16W,CHIP,CA CS00002JB38              R2105           
Q_RES_0402LF-0,5%,1/16W,CHIP,CA CS00002JB38              R2106           
Q_RES_0402LF-0,5%,1/16W,CHIP,CA CS00002JB38              R2107           
Q_RES_0402LF-0,5%,1/16W,CHIP,CA CS00002JB38              R2108           
Q_RES_0402LF-0,5%,1/16W,CHIP,CA CS00002JB38              R2109           
Q_RES_0402LF-0,5%,1/16W,CHIP,CA CS00002JB38              R2110           
Q_RES_0402LF-0,5%,1/16W,CHIP,CA CS00002JB38              R2111           
Q_RES_0402LF-0,5%,1/16W,CHIP,CA CS00002JB38              R2112           
Q_RES_0402LF-0,5%,1/16W,CHIP,CA CS00002JB38              R2113           
Q_RES_0402LF-0,5%,1/16W,CHIP,CA CS00002JB38              R2114           
Q_RES_0402LF-0,5%,1/16W,CHIP,CA CS00002JB38              R2115           
Q_RES_0402LF-0,5%,1/16W,CHIP,CA CS00002JB38              R2116           
Q_RES_0402LF-0,5%,1/16W,CHIP,CA CS00002JB38              R2117           
Q_RES_0402LF-0,5%,1/16W,CHIP,CA CS00002JB38              R2118           
Q_RES_0402LF-0,5%,1/16W,CHIP,CA CS00002JB38              R2119           
Q_RES_0402LF-0,5%,1/16W,CHIP,CA CS00002JB38              R2120           
Q_RES_0402LF-0,5%,1/16W,CHIP,CA CS00002JB38              R2130           
Q_RES_0402LF-0,5%,1/16W,CHIP,CA CS00002JB38              R2131           
Q_RES_0402LF-0,5%,1/16W,CHIP,CA CS00002JB38              R2135           
Q_RES_0402LF-0,5%,1/16W,CHIP,CA CS00002JB38              R2139           
Q_RES_0402LF-0,5%,1/16W,CHIP,CA CS00002JB38              R2143           
Q_RES_0402LF-0,5%,1/16W,CHIP,CA CS00002JB38              R2144           
Q_RES_0402LF-0,5%,1/16W,CHIP,CA CS00002JB38              R2145           
Q_RES_0402LF-0,5%,1/16W,CHIP,CA CS00002JB38              R2146           
Q_RES_0402LF-0,5%,1/16W,CHIP,CA CS00002JB38              R2147           
Q_RES_0402LF-0,5%,1/16W,CHIP,CA CS00002JB38              R2148           
Q_RES_0402LF-0,5%,1/16W,CHIP,CA CS00002JB38              R2149           
Q_RES_0402LF-0,5%,1/16W,CHIP,CA CS00002JB38              R2150           
Q_RES_0402LF-0,5%,1/16W,CHIP,CA CS00002JB38              R2151           
Q_RES_0402LF-0,5%,1/16W,CHIP,CA CS00002JB38              R2152           
Q_RES_0402LF-0,5%,1/16W,CHIP,CA CS00002JB38              R2153           
Q_RES_0402LF-0,5%,1/16W,CHIP,CA CS00002JB38              R2154           
Q_RES_0402LF-0,5%,1/16W,CHIP,CA CS00002JB38              R2155           
Q_RES_0402LF-0,5%,1/16W,CHIP,CA CS00002JB38              R2156           
Q_RES_0402LF-0,5%,1/16W,CHIP,CA CS00002JB38              R2159           
Q_RES_0402LF-0,5%,1/16W,CHIP,CA CS00002JB38              R2160           
Q_RES_0402LF-0,5%,1/16W,CHIP,CA CS00002JB38              R2161           
Q_RES_0402LF-0,5%,1/16W,CHIP,CA CS00002JB38              R2162           
Q_RES_0402LF-0,5%,1/16W,CHIP,CA CS00002JB38              R2163           
Q_RES_0402LF-0,5%,1/16W,CHIP,CA CS00002JB38              R2164           
Q_RES_0402LF-0,5%,1/16W,CHIP,CA CS00002JB38              R2165           
Q_RES_0402LF-0,5%,1/16W,CHIP,CA CS00002JB38              R2166           
Q_RES_0402LF-0,5%,1/16W,CHIP,CA CS00002JB38              R2169           
Q_RES_0402LF-0,5%,1/16W,CHIP,CA CS00002JB38              R2181           
Q_RES_0402LF-0,5%,1/16W,CHIP,CA CS00002JB38              R2182           
Q_RES_0402LF-0,5%,1/16W,CHIP,CA CS00002JB38              R2183           
Q_RES_0402LF-0,5%,1/16W,CHIP,CA CS00002JB38              R2184           
Q_RES_0402LF-0,5%,1/16W,CHIP,CA CS00002JB38              R2185           
Q_RES_0402LF-0,5%,1/16W,CHIP,CA CS00002JB38              R2187           
Q_RES_0402LF-0,5%,1/16W,CHIP,CA CS00002JB38              R2188           
Q_RES_0402LF-0,5%,1/16W,CHIP,CA CS00002JB38              R2189           
Q_RES_0402LF-0,5%,1/16W,CHIP,CA CS00002JB38              R2190           
Q_RES_0402LF-0,5%,1/16W,CHIP,CA CS00002JB38              R2208           
Q_RES_0402LF-0,5%,1/16W,CHIP,CA CS00002JB38              R2209           
Q_RES_0402LF-0,5%,1/16W,CHIP,CA CS00002JB38              R2210           
Q_RES_0402LF-0,5%,1/16W,CHIP,CA CS00002JB38              R2211           
Q_RES_0402LF-0,5%,1/16W,CHIP,CA CS00002JB38              R2380           
Q_RES_0402LF-0,5%,1/16W,CHIP,CA CS00002JB38              R2387           

----------------

Q_RES_0402LF-0,5%,1/16W,EMPTY,A CS00002JB38              PR107           
Q_RES_0402LF-0,5%,1/16W,EMPTY,A CS00002JB38              PR157           
Q_RES_0402LF-0,5%,1/16W,EMPTY,A CS00002JB38              PR260           
Q_RES_0402LF-0,5%,1/16W,EMPTY,A CS00002JB38              PR304           
Q_RES_0402LF-0,5%,1/16W,EMPTY,A CS00002JB38              PR396           
Q_RES_0402LF-0,5%,1/16W,EMPTY,A CS00002JB38              PR403           
Q_RES_0402LF-0,5%,1/16W,EMPTY,A CS00002JB38              PR409           
Q_RES_0402LF-0,5%,1/16W,EMPTY,A CS00002JB38              PR410           
Q_RES_0402LF-0,5%,1/16W,EMPTY,A CS00002JB38              PR412           
Q_RES_0402LF-0,5%,1/16W,EMPTY,A CS00002JB38              PR441           
Q_RES_0402LF-0,5%,1/16W,EMPTY,A CS00002JB38              PR443           
Q_RES_0402LF-0,5%,1/16W,EMPTY,A CS00002JB38              PR450           
Q_RES_0402LF-0,5%,1/16W,EMPTY,A CS00002JB38              PR452           
Q_RES_0402LF-0,5%,1/16W,EMPTY,A CS00002JB38              PR632           
Q_RES_0402LF-0,5%,1/16W,EMPTY,A CS00002JB38              PR633           
Q_RES_0402LF-0,5%,1/16W,EMPTY,A CS00002JB38              PR636           
Q_RES_0402LF-0,5%,1/16W,EMPTY,A CS00002JB38              PR640           
Q_RES_0402LF-0,5%,1/16W,EMPTY,A CS00002JB38              PR677           
Q_RES_0402LF-0,5%,1/16W,EMPTY,A CS00002JB38              PR699           
Q_RES_0402LF-0,5%,1/16W,EMPTY,A CS00002JB38              PR703           
Q_RES_0402LF-0,5%,1/16W,EMPTY,A CS00002JB38              PR704           
Q_RES_0402LF-0,5%,1/16W,EMPTY,A CS00002JB38              PR707           
Q_RES_0402LF-0,5%,1/16W,EMPTY,A CS00002JB38              PR1324          
Q_RES_0402LF-0,5%,1/16W,EMPTY,A CS00002JB38              PR1325          
Q_RES_0402LF-0,5%,1/16W,EMPTY,A CS00002JB38              PR1335          
Q_RES_0402LF-0,5%,1/16W,EMPTY,A CS00002JB38              PR1388          
Q_RES_0402LF-0,5%,1/16W,EMPTY,A CS00002JB38              R143            
Q_RES_0402LF-0,5%,1/16W,EMPTY,A CS00002JB38              R423            
Q_RES_0402LF-0,5%,1/16W,EMPTY,A CS00002JB38              R448            
Q_RES_0402LF-0,5%,1/16W,EMPTY,A CS00002JB38              R507            
Q_RES_0402LF-0,5%,1/16W,EMPTY,A CS00002JB38              R508            
Q_RES_0402LF-0,5%,1/16W,EMPTY,A CS00002JB38              R631            
Q_RES_0402LF-0,5%,1/16W,EMPTY,A CS00002JB38              R632            
Q_RES_0402LF-0,5%,1/16W,EMPTY,A CS00002JB38              R633            
Q_RES_0402LF-0,5%,1/16W,EMPTY,A CS00002JB38              R665            
Q_RES_0402LF-0,5%,1/16W,EMPTY,A CS00002JB38              R666            
Q_RES_0402LF-0,5%,1/16W,EMPTY,A CS00002JB38              R667            
Q_RES_0402LF-0,5%,1/16W,EMPTY,A CS00002JB38              R668            
Q_RES_0402LF-0,5%,1/16W,EMPTY,A CS00002JB38              R682            
Q_RES_0402LF-0,5%,1/16W,EMPTY,A CS00002JB38              R683            
Q_RES_0402LF-0,5%,1/16W,EMPTY,A CS00002JB38              R684            
Q_RES_0402LF-0,5%,1/16W,EMPTY,A CS00002JB38              R685            
Q_RES_0402LF-0,5%,1/16W,EMPTY,A CS00002JB38              R1013           
Q_RES_0402LF-0,5%,1/16W,EMPTY,A CS00002JB38              R1015           
Q_RES_0402LF-0,5%,1/16W,EMPTY,A CS00002JB38              R1017           
Q_RES_0402LF-0,5%,1/16W,EMPTY,A CS00002JB38              R1019           
Q_RES_0402LF-0,5%,1/16W,EMPTY,A CS00002JB38              R1135           
Q_RES_0402LF-0,5%,1/16W,EMPTY,A CS00002JB38              R1559           
Q_RES_0402LF-0,5%,1/16W,EMPTY,A CS00002JB38              R1560           
Q_RES_0402LF-0,5%,1/16W,EMPTY,A CS00002JB38              R1640           
Q_RES_0402LF-0,5%,1/16W,EMPTY,A CS00002JB38              R1648           
Q_RES_0402LF-0,5%,1/16W,EMPTY,A CS00002JB38              R1695           
Q_RES_0402LF-0,5%,1/16W,EMPTY,A CS00002JB38              R1720           
Q_RES_0402LF-0,5%,1/16W,EMPTY,A CS00002JB38              R1745           
Q_RES_0402LF-0,5%,1/16W,EMPTY,A CS00002JB38              R1759           
Q_RES_0402LF-0,5%,1/16W,EMPTY,A CS00002JB38              R1760           
Q_RES_0402LF-0,5%,1/16W,EMPTY,A CS00002JB38              R1778           
Q_RES_0402LF-0,5%,1/16W,EMPTY,A CS00002JB38              R1821           
Q_RES_0402LF-0,5%,1/16W,EMPTY,A CS00002JB38              R1829           
Q_RES_0402LF-0,5%,1/16W,EMPTY,A CS00002JB38              R1830           
Q_RES_0402LF-0,5%,1/16W,EMPTY,A CS00002JB38              R1831           
Q_RES_0402LF-0,5%,1/16W,EMPTY,A CS00002JB38              R1832           
Q_RES_0402LF-0,5%,1/16W,EMPTY,A CS00002JB38              R1839           
Q_RES_0402LF-0,5%,1/16W,EMPTY,A CS00002JB38              R1840           
Q_RES_0402LF-0,5%,1/16W,EMPTY,A CS00002JB38              R2071           
Q_RES_0402LF-0,5%,1/16W,EMPTY,A CS00002JB38              R2132           
Q_RES_0402LF-0,5%,1/16W,EMPTY,A CS00002JB38              R2334           

----------------

Q_RES_0402LF-1,1%,1/16W,CHIP,CA CS-1002FB23              PR130           
Q_RES_0402LF-1,1%,1/16W,CHIP,CA CS-1002FB23              PR176           
Q_RES_0402LF-1,1%,1/16W,CHIP,CA CS-1002FB23              PR220           
Q_RES_0402LF-1,1%,1/16W,CHIP,CA CS-1002FB23              PR283           
Q_RES_0402LF-1,1%,1/16W,CHIP,CA CS-1002FB23              PR323           
Q_RES_0402LF-1,1%,1/16W,CHIP,CA CS-1002FB23              PR375           
Q_RES_0402LF-1,1%,1/16W,CHIP,CA CS-1002FB23              PR389           

----------------

Q_RES_0402LF-1.33K,1%,1/16W,CHA CS21332FB05              R1103           
Q_RES_0402LF-1.33K,1%,1/16W,CHA CS21332FB05              R2016           
Q_RES_0402LF-1.33K,1%,1/16W,CHA CS21332FB05              R2020           
Q_RES_0402LF-1.33K,1%,1/16W,CHA CS21332FB05              R2021           

----------------

Q_RES_0402LF-1.5K,1%,1/16W,EMPA CS21502FB14              PR833           

----------------

Q_RES_0402LF-10,1%,1/16W,CHIP,A CS01002FB21              R1              
Q_RES_0402LF-10,1%,1/16W,CHIP,A CS01002FB21              R24             
Q_RES_0402LF-10,1%,1/16W,CHIP,A CS01002FB21              R25             
Q_RES_0402LF-10,1%,1/16W,CHIP,A CS01002FB21              R53             
Q_RES_0402LF-10,1%,1/16W,CHIP,A CS01002FB21              R54             
Q_RES_0402LF-10,1%,1/16W,CHIP,A CS01002FB21              R61             
Q_RES_0402LF-10,1%,1/16W,CHIP,A CS01002FB21              R144            
Q_RES_0402LF-10,1%,1/16W,CHIP,A CS01002FB21              R752            
Q_RES_0402LF-10,1%,1/16W,CHIP,A CS01002FB21              R753            
Q_RES_0402LF-10,1%,1/16W,CHIP,A CS01002FB21              R754            
Q_RES_0402LF-10,1%,1/16W,CHIP,A CS01002FB21              R755            
Q_RES_0402LF-10,1%,1/16W,CHIP,A CS01002FB21              R756            
Q_RES_0402LF-10,1%,1/16W,CHIP,A CS01002FB21              R763            
Q_RES_0402LF-10,1%,1/16W,CHIP,A CS01002FB21              R775            
Q_RES_0402LF-10,1%,1/16W,CHIP,A CS01002FB21              R777            

----------------

Q_RES_0402LF-100,1%,1/16W,CHIPA CS11002FB22              PR519           
Q_RES_0402LF-100,1%,1/16W,CHIPA CS11002FB22              PR520           
Q_RES_0402LF-100,1%,1/16W,CHIPA CS11002FB22              PR521           
Q_RES_0402LF-100,1%,1/16W,CHIPA CS11002FB22              PR522           
Q_RES_0402LF-100,1%,1/16W,CHIPA CS11002FB22              PR527           
Q_RES_0402LF-100,1%,1/16W,CHIPA CS11002FB22              PR528           
Q_RES_0402LF-100,1%,1/16W,CHIPA CS11002FB22              PR531           
Q_RES_0402LF-100,1%,1/16W,CHIPA CS11002FB22              PR558           
Q_RES_0402LF-100,1%,1/16W,CHIPA CS11002FB22              PR559           
Q_RES_0402LF-100,1%,1/16W,CHIPA CS11002FB22              PR560           
Q_RES_0402LF-100,1%,1/16W,CHIPA CS11002FB22              PR561           
Q_RES_0402LF-100,1%,1/16W,CHIPA CS11002FB22              PR566           
Q_RES_0402LF-100,1%,1/16W,CHIPA CS11002FB22              PR567           
Q_RES_0402LF-100,1%,1/16W,CHIPA CS11002FB22              PR568           
Q_RES_0402LF-100,1%,1/16W,CHIPA CS11002FB22              PR569           
Q_RES_0402LF-100,1%,1/16W,CHIPA CS11002FB22              PR574           
Q_RES_0402LF-100,1%,1/16W,CHIPA CS11002FB22              PR575           
Q_RES_0402LF-100,1%,1/16W,CHIPA CS11002FB22              PR578           
Q_RES_0402LF-100,1%,1/16W,CHIPA CS11002FB22              PR586           
Q_RES_0402LF-100,1%,1/16W,CHIPA CS11002FB22              PR587           
Q_RES_0402LF-100,1%,1/16W,CHIPA CS11002FB22              PR591           
Q_RES_0402LF-100,1%,1/16W,CHIPA CS11002FB22              PR592           
Q_RES_0402LF-100,1%,1/16W,CHIPA CS11002FB22              PR1747          
Q_RES_0402LF-100,1%,1/16W,CHIPA CS11002FB22              R2              
Q_RES_0402LF-100,1%,1/16W,CHIPA CS11002FB22              R5              
Q_RES_0402LF-100,1%,1/16W,CHIPA CS11002FB22              R6              
Q_RES_0402LF-100,1%,1/16W,CHIPA CS11002FB22              R22             
Q_RES_0402LF-100,1%,1/16W,CHIPA CS11002FB22              R23             
Q_RES_0402LF-100,1%,1/16W,CHIPA CS11002FB22              R51             
Q_RES_0402LF-100,1%,1/16W,CHIPA CS11002FB22              R52             
Q_RES_0402LF-100,1%,1/16W,CHIPA CS11002FB22              R62             
Q_RES_0402LF-100,1%,1/16W,CHIPA CS11002FB22              R65             
Q_RES_0402LF-100,1%,1/16W,CHIPA CS11002FB22              R66             
Q_RES_0402LF-100,1%,1/16W,CHIPA CS11002FB22              R328            
Q_RES_0402LF-100,1%,1/16W,CHIPA CS11002FB22              R495            
Q_RES_0402LF-100,1%,1/16W,CHIPA CS11002FB22              R555            
Q_RES_0402LF-100,1%,1/16W,CHIPA CS11002FB22              R557            
Q_RES_0402LF-100,1%,1/16W,CHIPA CS11002FB22              R559            
Q_RES_0402LF-100,1%,1/16W,CHIPA CS11002FB22              R776            
Q_RES_0402LF-100,1%,1/16W,CHIPA CS11002FB22              R1024           
Q_RES_0402LF-100,1%,1/16W,CHIPA CS11002FB22              R1200           
Q_RES_0402LF-100,1%,1/16W,CHIPA CS11002FB22              R1425           
Q_RES_0402LF-100,1%,1/16W,CHIPA CS11002FB22              R1426           
Q_RES_0402LF-100,1%,1/16W,CHIPA CS11002FB22              R1427           
Q_RES_0402LF-100,1%,1/16W,CHIPA CS11002FB22              R1428           
Q_RES_0402LF-100,1%,1/16W,CHIPA CS11002FB22              R1429           
Q_RES_0402LF-100,1%,1/16W,CHIPA CS11002FB22              R1430           
Q_RES_0402LF-100,1%,1/16W,CHIPA CS11002FB22              R1487           
Q_RES_0402LF-100,1%,1/16W,CHIPA CS11002FB22              R1574           
Q_RES_0402LF-100,1%,1/16W,CHIPA CS11002FB22              R1578           
Q_RES_0402LF-100,1%,1/16W,CHIPA CS11002FB22              R1614           
Q_RES_0402LF-100,1%,1/16W,CHIPA CS11002FB22              R1616           
Q_RES_0402LF-100,1%,1/16W,CHIPA CS11002FB22              R1618           
Q_RES_0402LF-100,1%,1/16W,CHIPA CS11002FB22              R1641           
Q_RES_0402LF-100,1%,1/16W,CHIPA CS11002FB22              R1735           
Q_RES_0402LF-100,1%,1/16W,CHIPA CS11002FB22              R1738           
Q_RES_0402LF-100,1%,1/16W,CHIPA CS11002FB22              R1739           
Q_RES_0402LF-100,1%,1/16W,CHIPA CS11002FB22              R1856           
Q_RES_0402LF-100,1%,1/16W,CHIPA CS11002FB22              R1895           
Q_RES_0402LF-100,1%,1/16W,CHIPA CS11002FB22              R1896           
Q_RES_0402LF-100,1%,1/16W,CHIPA CS11002FB22              R1897           
Q_RES_0402LF-100,1%,1/16W,CHIPA CS11002FB22              R1898           
Q_RES_0402LF-100,1%,1/16W,CHIPA CS11002FB22              R1956           
Q_RES_0402LF-100,1%,1/16W,CHIPA CS11002FB22              R1957           
Q_RES_0402LF-100,1%,1/16W,CHIPA CS11002FB22              R1972           
Q_RES_0402LF-100,1%,1/16W,CHIPA CS11002FB22              R1982           
Q_RES_0402LF-100,1%,1/16W,CHIPA CS11002FB22              R1992           
Q_RES_0402LF-100,1%,1/16W,CHIPA CS11002FB22              R2004           
Q_RES_0402LF-100,1%,1/16W,CHIPA CS11002FB22              R2172           

----------------

Q_RES_0402LF-100,1%,1/16W,CHIPB CS11002FB07              R1366           
Q_RES_0402LF-100,1%,1/16W,CHIPB CS11002FB07              R1367           

----------------

Q_RES_0402LF-100,1%,1/16W,EMPTA CS11002FB22              R135            
Q_RES_0402LF-100,1%,1/16W,EMPTA CS11002FB22              R137            
Q_RES_0402LF-100,1%,1/16W,EMPTA CS11002FB22              R151            
Q_RES_0402LF-100,1%,1/16W,EMPTA CS11002FB22              R153            
Q_RES_0402LF-100,1%,1/16W,EMPTA CS11002FB22              R155            
Q_RES_0402LF-100,1%,1/16W,EMPTA CS11002FB22              R157            
Q_RES_0402LF-100,1%,1/16W,EMPTA CS11002FB22              R175            
Q_RES_0402LF-100,1%,1/16W,EMPTA CS11002FB22              R177            
Q_RES_0402LF-100,1%,1/16W,EMPTA CS11002FB22              R179            
Q_RES_0402LF-100,1%,1/16W,EMPTA CS11002FB22              R181            
Q_RES_0402LF-100,1%,1/16W,EMPTA CS11002FB22              R183            
Q_RES_0402LF-100,1%,1/16W,EMPTA CS11002FB22              R185            
Q_RES_0402LF-100,1%,1/16W,EMPTA CS11002FB22              R199            
Q_RES_0402LF-100,1%,1/16W,EMPTA CS11002FB22              R200            
Q_RES_0402LF-100,1%,1/16W,EMPTA CS11002FB22              R201            
Q_RES_0402LF-100,1%,1/16W,EMPTA CS11002FB22              R202            
Q_RES_0402LF-100,1%,1/16W,EMPTA CS11002FB22              R219            
Q_RES_0402LF-100,1%,1/16W,EMPTA CS11002FB22              R220            
Q_RES_0402LF-100,1%,1/16W,EMPTA CS11002FB22              R243            
Q_RES_0402LF-100,1%,1/16W,EMPTA CS11002FB22              R244            
Q_RES_0402LF-100,1%,1/16W,EMPTA CS11002FB22              R561            
Q_RES_0402LF-100,1%,1/16W,EMPTA CS11002FB22              R1370           
Q_RES_0402LF-100,1%,1/16W,EMPTA CS11002FB22              R2354           

----------------

Q_RES_0402LF-100K,1%,1/16W,CHIA CS41002FB28              PR831           
Q_RES_0402LF-100K,1%,1/16W,CHIA CS41002FB28              R413            
Q_RES_0402LF-100K,1%,1/16W,CHIA CS41002FB28              R1289           
Q_RES_0402LF-100K,1%,1/16W,CHIA CS41002FB28              R1350           
Q_RES_0402LF-100K,1%,1/16W,CHIA CS41002FB28              R1351           
Q_RES_0402LF-100K,1%,1/16W,CHIA CS41002FB28              R1352           
Q_RES_0402LF-100K,1%,1/16W,CHIA CS41002FB28              R1353           
Q_RES_0402LF-100K,1%,1/16W,CHIA CS41002FB28              R1354           
Q_RES_0402LF-100K,1%,1/16W,CHIA CS41002FB28              R1355           
Q_RES_0402LF-100K,1%,1/16W,CHIA CS41002FB28              R1541           
Q_RES_0402LF-100K,1%,1/16W,CHIA CS41002FB28              R1688           
Q_RES_0402LF-100K,1%,1/16W,CHIA CS41002FB28              R1692           
Q_RES_0402LF-100K,1%,1/16W,CHIA CS41002FB28              R2072           
Q_RES_0402LF-100K,1%,1/16W,CHIA CS41002FB28              R2073           
Q_RES_0402LF-100K,1%,1/16W,CHIA CS41002FB28              R2084           
Q_RES_0402LF-100K,1%,1/16W,CHIA CS41002FB28              R2085           

----------------

Q_RES_0402LF-100K,1%,1/16W,EMPA CS41002FB09              R2014           
Q_RES_0402LF-100K,1%,1/16W,EMPA CS41002FB09              R2015           
Q_RES_0402LF-100K,1%,1/16W,EMPA CS41002FB09              R2018           
Q_RES_0402LF-100K,1%,1/16W,EMPA CS41002FB09              R2019           
Q_RES_0402LF-100K,1%,1/16W,EMPA CS41002FB09              R2036           
Q_RES_0402LF-100K,1%,1/16W,EMPA CS41002FB09              R2037           
Q_RES_0402LF-100K,1%,1/16W,EMPA CS41002FB09              R2042           
Q_RES_0402LF-100K,1%,1/16W,EMPA CS41002FB09              R2043           

----------------

Q_RES_0402LF-100K,1%,1/16W,EMPB CS41002FB28              R1540           
Q_RES_0402LF-100K,1%,1/16W,EMPB CS41002FB28              R1701           

----------------

Q_RES_0402LF-100K,5%,1/16W,CHIA CS41002JB20              R461            
Q_RES_0402LF-100K,5%,1/16W,CHIA CS41002JB20              R1643           

----------------

Q_RES_0402LF-10K,1%,1/16W,CHIPA CS31002FB26              PR186           
Q_RES_0402LF-10K,1%,1/16W,CHIPA CS31002FB26              PR187           
Q_RES_0402LF-10K,1%,1/16W,CHIPA CS31002FB26              PR1302          
Q_RES_0402LF-10K,1%,1/16W,CHIPA CS31002FB26              PR1313          
Q_RES_0402LF-10K,1%,1/16W,CHIPA CS31002FB26              PR1317          
Q_RES_0402LF-10K,1%,1/16W,CHIPA CS31002FB26              PR1320          
Q_RES_0402LF-10K,1%,1/16W,CHIPA CS31002FB26              R8              
Q_RES_0402LF-10K,1%,1/16W,CHIPA CS31002FB26              R26             
Q_RES_0402LF-10K,1%,1/16W,CHIPA CS31002FB26              R34             
Q_RES_0402LF-10K,1%,1/16W,CHIPA CS31002FB26              R42             
Q_RES_0402LF-10K,1%,1/16W,CHIPA CS31002FB26              R69             
Q_RES_0402LF-10K,1%,1/16W,CHIPA CS31002FB26              R70             
Q_RES_0402LF-10K,1%,1/16W,CHIPA CS31002FB26              R71             
Q_RES_0402LF-10K,1%,1/16W,CHIPA CS31002FB26              R79             
Q_RES_0402LF-10K,1%,1/16W,CHIPA CS31002FB26              R111            
Q_RES_0402LF-10K,1%,1/16W,CHIPA CS31002FB26              R139            
Q_RES_0402LF-10K,1%,1/16W,CHIPA CS31002FB26              R148            
Q_RES_0402LF-10K,1%,1/16W,CHIPA CS31002FB26              R270            
Q_RES_0402LF-10K,1%,1/16W,CHIPA CS31002FB26              R271            
Q_RES_0402LF-10K,1%,1/16W,CHIPA CS31002FB26              R272            
Q_RES_0402LF-10K,1%,1/16W,CHIPA CS31002FB26              R273            
Q_RES_0402LF-10K,1%,1/16W,CHIPA CS31002FB26              R274            
Q_RES_0402LF-10K,1%,1/16W,CHIPA CS31002FB26              R283            
Q_RES_0402LF-10K,1%,1/16W,CHIPA CS31002FB26              R284            
Q_RES_0402LF-10K,1%,1/16W,CHIPA CS31002FB26              R285            
Q_RES_0402LF-10K,1%,1/16W,CHIPA CS31002FB26              R286            
Q_RES_0402LF-10K,1%,1/16W,CHIPA CS31002FB26              R287            
Q_RES_0402LF-10K,1%,1/16W,CHIPA CS31002FB26              R318            
Q_RES_0402LF-10K,1%,1/16W,CHIPA CS31002FB26              R319            
Q_RES_0402LF-10K,1%,1/16W,CHIPA CS31002FB26              R320            
Q_RES_0402LF-10K,1%,1/16W,CHIPA CS31002FB26              R321            
Q_RES_0402LF-10K,1%,1/16W,CHIPA CS31002FB26              R325            
Q_RES_0402LF-10K,1%,1/16W,CHIPA CS31002FB26              R326            
Q_RES_0402LF-10K,1%,1/16W,CHIPA CS31002FB26              R327            
Q_RES_0402LF-10K,1%,1/16W,CHIPA CS31002FB26              R332            
Q_RES_0402LF-10K,1%,1/16W,CHIPA CS31002FB26              R334            
Q_RES_0402LF-10K,1%,1/16W,CHIPA CS31002FB26              R372            
Q_RES_0402LF-10K,1%,1/16W,CHIPA CS31002FB26              R375            
Q_RES_0402LF-10K,1%,1/16W,CHIPA CS31002FB26              R381            
Q_RES_0402LF-10K,1%,1/16W,CHIPA CS31002FB26              R388            
Q_RES_0402LF-10K,1%,1/16W,CHIPA CS31002FB26              R391            
Q_RES_0402LF-10K,1%,1/16W,CHIPA CS31002FB26              R395            
Q_RES_0402LF-10K,1%,1/16W,CHIPA CS31002FB26              R396            
Q_RES_0402LF-10K,1%,1/16W,CHIPA CS31002FB26              R399            
Q_RES_0402LF-10K,1%,1/16W,CHIPA CS31002FB26              R400            
Q_RES_0402LF-10K,1%,1/16W,CHIPA CS31002FB26              R404            
Q_RES_0402LF-10K,1%,1/16W,CHIPA CS31002FB26              R453            
Q_RES_0402LF-10K,1%,1/16W,CHIPA CS31002FB26              R456            
Q_RES_0402LF-10K,1%,1/16W,CHIPA CS31002FB26              R463            
Q_RES_0402LF-10K,1%,1/16W,CHIPA CS31002FB26              R498            
Q_RES_0402LF-10K,1%,1/16W,CHIPA CS31002FB26              R515            
Q_RES_0402LF-10K,1%,1/16W,CHIPA CS31002FB26              R608            
Q_RES_0402LF-10K,1%,1/16W,CHIPA CS31002FB26              R610            
Q_RES_0402LF-10K,1%,1/16W,CHIPA CS31002FB26              R613            
Q_RES_0402LF-10K,1%,1/16W,CHIPA CS31002FB26              R618            
Q_RES_0402LF-10K,1%,1/16W,CHIPA CS31002FB26              R619            
Q_RES_0402LF-10K,1%,1/16W,CHIPA CS31002FB26              R624            
Q_RES_0402LF-10K,1%,1/16W,CHIPA CS31002FB26              R626            
Q_RES_0402LF-10K,1%,1/16W,CHIPA CS31002FB26              R628            
Q_RES_0402LF-10K,1%,1/16W,CHIPA CS31002FB26              R635            
Q_RES_0402LF-10K,1%,1/16W,CHIPA CS31002FB26              R645            
Q_RES_0402LF-10K,1%,1/16W,CHIPA CS31002FB26              R719            
Q_RES_0402LF-10K,1%,1/16W,CHIPA CS31002FB26              R721            
Q_RES_0402LF-10K,1%,1/16W,CHIPA CS31002FB26              R727            
Q_RES_0402LF-10K,1%,1/16W,CHIPA CS31002FB26              R730            
Q_RES_0402LF-10K,1%,1/16W,CHIPA CS31002FB26              R735            
Q_RES_0402LF-10K,1%,1/16W,CHIPA CS31002FB26              R739            
Q_RES_0402LF-10K,1%,1/16W,CHIPA CS31002FB26              R740            
Q_RES_0402LF-10K,1%,1/16W,CHIPA CS31002FB26              R769            
Q_RES_0402LF-10K,1%,1/16W,CHIPA CS31002FB26              R770            
Q_RES_0402LF-10K,1%,1/16W,CHIPA CS31002FB26              R783            
Q_RES_0402LF-10K,1%,1/16W,CHIPA CS31002FB26              R913            
Q_RES_0402LF-10K,1%,1/16W,CHIPA CS31002FB26              R919            
Q_RES_0402LF-10K,1%,1/16W,CHIPA CS31002FB26              R927            
Q_RES_0402LF-10K,1%,1/16W,CHIPA CS31002FB26              R928            
Q_RES_0402LF-10K,1%,1/16W,CHIPA CS31002FB26              R929            
Q_RES_0402LF-10K,1%,1/16W,CHIPA CS31002FB26              R932            
Q_RES_0402LF-10K,1%,1/16W,CHIPA CS31002FB26              R933            
Q_RES_0402LF-10K,1%,1/16W,CHIPA CS31002FB26              R934            
Q_RES_0402LF-10K,1%,1/16W,CHIPA CS31002FB26              R935            
Q_RES_0402LF-10K,1%,1/16W,CHIPA CS31002FB26              R936            
Q_RES_0402LF-10K,1%,1/16W,CHIPA CS31002FB26              R937            
Q_RES_0402LF-10K,1%,1/16W,CHIPA CS31002FB26              R938            
Q_RES_0402LF-10K,1%,1/16W,CHIPA CS31002FB26              R939            
Q_RES_0402LF-10K,1%,1/16W,CHIPA CS31002FB26              R989            
Q_RES_0402LF-10K,1%,1/16W,CHIPA CS31002FB26              R1099           
Q_RES_0402LF-10K,1%,1/16W,CHIPA CS31002FB26              R1104           
Q_RES_0402LF-10K,1%,1/16W,CHIPA CS31002FB26              R1106           
Q_RES_0402LF-10K,1%,1/16W,CHIPA CS31002FB26              R1133           
Q_RES_0402LF-10K,1%,1/16W,CHIPA CS31002FB26              R1138           
Q_RES_0402LF-10K,1%,1/16W,CHIPA CS31002FB26              R1143           
Q_RES_0402LF-10K,1%,1/16W,CHIPA CS31002FB26              R1149           
Q_RES_0402LF-10K,1%,1/16W,CHIPA CS31002FB26              R1150           
Q_RES_0402LF-10K,1%,1/16W,CHIPA CS31002FB26              R1198           
Q_RES_0402LF-10K,1%,1/16W,CHIPA CS31002FB26              R1216           
Q_RES_0402LF-10K,1%,1/16W,CHIPA CS31002FB26              R1217           
Q_RES_0402LF-10K,1%,1/16W,CHIPA CS31002FB26              R1224           
Q_RES_0402LF-10K,1%,1/16W,CHIPA CS31002FB26              R1225           
Q_RES_0402LF-10K,1%,1/16W,CHIPA CS31002FB26              R1227           
Q_RES_0402LF-10K,1%,1/16W,CHIPA CS31002FB26              R1254           
Q_RES_0402LF-10K,1%,1/16W,CHIPA CS31002FB26              R1256           
Q_RES_0402LF-10K,1%,1/16W,CHIPA CS31002FB26              R1257           
Q_RES_0402LF-10K,1%,1/16W,CHIPA CS31002FB26              R1258           
Q_RES_0402LF-10K,1%,1/16W,CHIPA CS31002FB26              R1259           
Q_RES_0402LF-10K,1%,1/16W,CHIPA CS31002FB26              R1299           
Q_RES_0402LF-10K,1%,1/16W,CHIPA CS31002FB26              R1311           
Q_RES_0402LF-10K,1%,1/16W,CHIPA CS31002FB26              R1337           
Q_RES_0402LF-10K,1%,1/16W,CHIPA CS31002FB26              R1338           
Q_RES_0402LF-10K,1%,1/16W,CHIPA CS31002FB26              R1339           
Q_RES_0402LF-10K,1%,1/16W,CHIPA CS31002FB26              R1341           
Q_RES_0402LF-10K,1%,1/16W,CHIPA CS31002FB26              R1342           
Q_RES_0402LF-10K,1%,1/16W,CHIPA CS31002FB26              R1343           
Q_RES_0402LF-10K,1%,1/16W,CHIPA CS31002FB26              R1375           
Q_RES_0402LF-10K,1%,1/16W,CHIPA CS31002FB26              R1396           
Q_RES_0402LF-10K,1%,1/16W,CHIPA CS31002FB26              R1399           
Q_RES_0402LF-10K,1%,1/16W,CHIPA CS31002FB26              R1401           
Q_RES_0402LF-10K,1%,1/16W,CHIPA CS31002FB26              R1434           
Q_RES_0402LF-10K,1%,1/16W,CHIPA CS31002FB26              R1435           
Q_RES_0402LF-10K,1%,1/16W,CHIPA CS31002FB26              R1436           
Q_RES_0402LF-10K,1%,1/16W,CHIPA CS31002FB26              R1437           
Q_RES_0402LF-10K,1%,1/16W,CHIPA CS31002FB26              R1438           
Q_RES_0402LF-10K,1%,1/16W,CHIPA CS31002FB26              R1439           
Q_RES_0402LF-10K,1%,1/16W,CHIPA CS31002FB26              R1449           
Q_RES_0402LF-10K,1%,1/16W,CHIPA CS31002FB26              R1450           
Q_RES_0402LF-10K,1%,1/16W,CHIPA CS31002FB26              R1457           
Q_RES_0402LF-10K,1%,1/16W,CHIPA CS31002FB26              R1458           
Q_RES_0402LF-10K,1%,1/16W,CHIPA CS31002FB26              R1459           
Q_RES_0402LF-10K,1%,1/16W,CHIPA CS31002FB26              R1478           
Q_RES_0402LF-10K,1%,1/16W,CHIPA CS31002FB26              R1488           
Q_RES_0402LF-10K,1%,1/16W,CHIPA CS31002FB26              R1495           
Q_RES_0402LF-10K,1%,1/16W,CHIPA CS31002FB26              R1496           
Q_RES_0402LF-10K,1%,1/16W,CHIPA CS31002FB26              R1522           
Q_RES_0402LF-10K,1%,1/16W,CHIPA CS31002FB26              R1539           
Q_RES_0402LF-10K,1%,1/16W,CHIPA CS31002FB26              R1542           
Q_RES_0402LF-10K,1%,1/16W,CHIPA CS31002FB26              R1554           
Q_RES_0402LF-10K,1%,1/16W,CHIPA CS31002FB26              R1558           
Q_RES_0402LF-10K,1%,1/16W,CHIPA CS31002FB26              R1583           
Q_RES_0402LF-10K,1%,1/16W,CHIPA CS31002FB26              R1592           
Q_RES_0402LF-10K,1%,1/16W,CHIPA CS31002FB26              R1601           
Q_RES_0402LF-10K,1%,1/16W,CHIPA CS31002FB26              R1609           
Q_RES_0402LF-10K,1%,1/16W,CHIPA CS31002FB26              R1610           
Q_RES_0402LF-10K,1%,1/16W,CHIPA CS31002FB26              R1658           
Q_RES_0402LF-10K,1%,1/16W,CHIPA CS31002FB26              R1659           
Q_RES_0402LF-10K,1%,1/16W,CHIPA CS31002FB26              R1667           
Q_RES_0402LF-10K,1%,1/16W,CHIPA CS31002FB26              R1681           
Q_RES_0402LF-10K,1%,1/16W,CHIPA CS31002FB26              R1690           
Q_RES_0402LF-10K,1%,1/16W,CHIPA CS31002FB26              R1694           
Q_RES_0402LF-10K,1%,1/16W,CHIPA CS31002FB26              R1697           
Q_RES_0402LF-10K,1%,1/16W,CHIPA CS31002FB26              R1820           
Q_RES_0402LF-10K,1%,1/16W,CHIPA CS31002FB26              R1822           
Q_RES_0402LF-10K,1%,1/16W,CHIPA CS31002FB26              R1824           
Q_RES_0402LF-10K,1%,1/16W,CHIPA CS31002FB26              R1828           
Q_RES_0402LF-10K,1%,1/16W,CHIPA CS31002FB26              R1854           
Q_RES_0402LF-10K,1%,1/16W,CHIPA CS31002FB26              R1857           
Q_RES_0402LF-10K,1%,1/16W,CHIPA CS31002FB26              R1905           
Q_RES_0402LF-10K,1%,1/16W,CHIPA CS31002FB26              R1906           
Q_RES_0402LF-10K,1%,1/16W,CHIPA CS31002FB26              R1907           
Q_RES_0402LF-10K,1%,1/16W,CHIPA CS31002FB26              R1908           
Q_RES_0402LF-10K,1%,1/16W,CHIPA CS31002FB26              R1955           
Q_RES_0402LF-10K,1%,1/16W,CHIPA CS31002FB26              R1958           
Q_RES_0402LF-10K,1%,1/16W,CHIPA CS31002FB26              R1961           
Q_RES_0402LF-10K,1%,1/16W,CHIPA CS31002FB26              R1963           
Q_RES_0402LF-10K,1%,1/16W,CHIPA CS31002FB26              R1970           
Q_RES_0402LF-10K,1%,1/16W,CHIPA CS31002FB26              R1973           
Q_RES_0402LF-10K,1%,1/16W,CHIPA CS31002FB26              R1979           
Q_RES_0402LF-10K,1%,1/16W,CHIPA CS31002FB26              R1980           
Q_RES_0402LF-10K,1%,1/16W,CHIPA CS31002FB26              R1983           
Q_RES_0402LF-10K,1%,1/16W,CHIPA CS31002FB26              R1989           
Q_RES_0402LF-10K,1%,1/16W,CHIPA CS31002FB26              R1990           
Q_RES_0402LF-10K,1%,1/16W,CHIPA CS31002FB26              R1993           
Q_RES_0402LF-10K,1%,1/16W,CHIPA CS31002FB26              R2001           
Q_RES_0402LF-10K,1%,1/16W,CHIPA CS31002FB26              R2002           
Q_RES_0402LF-10K,1%,1/16W,CHIPA CS31002FB26              R2017           
Q_RES_0402LF-10K,1%,1/16W,CHIPA CS31002FB26              R2022           
Q_RES_0402LF-10K,1%,1/16W,CHIPA CS31002FB26              R2023           
Q_RES_0402LF-10K,1%,1/16W,CHIPA CS31002FB26              R2040           
Q_RES_0402LF-10K,1%,1/16W,CHIPA CS31002FB26              R2041           
Q_RES_0402LF-10K,1%,1/16W,CHIPA CS31002FB26              R2046           
Q_RES_0402LF-10K,1%,1/16W,CHIPA CS31002FB26              R2047           
Q_RES_0402LF-10K,1%,1/16W,CHIPA CS31002FB26              R2134           
Q_RES_0402LF-10K,1%,1/16W,CHIPA CS31002FB26              R2138           
Q_RES_0402LF-10K,1%,1/16W,CHIPA CS31002FB26              R2167           
Q_RES_0402LF-10K,1%,1/16W,CHIPA CS31002FB26              R2180           
Q_RES_0402LF-10K,1%,1/16W,CHIPA CS31002FB26              R2193           
Q_RES_0402LF-10K,1%,1/16W,CHIPA CS31002FB26              R2197           

----------------

Q_RES_0402LF-10K,1%,1/16W,EMPTA CS31002FB26              PR1309          
Q_RES_0402LF-10K,1%,1/16W,EMPTA CS31002FB26              PR1647          
Q_RES_0402LF-10K,1%,1/16W,EMPTA CS31002FB26              R112            
Q_RES_0402LF-10K,1%,1/16W,EMPTA CS31002FB26              R197            
Q_RES_0402LF-10K,1%,1/16W,EMPTA CS31002FB26              R198            
Q_RES_0402LF-10K,1%,1/16W,EMPTA CS31002FB26              R401            
Q_RES_0402LF-10K,1%,1/16W,EMPTA CS31002FB26              R454            
Q_RES_0402LF-10K,1%,1/16W,EMPTA CS31002FB26              R536            
Q_RES_0402LF-10K,1%,1/16W,EMPTA CS31002FB26              R538            
Q_RES_0402LF-10K,1%,1/16W,EMPTA CS31002FB26              R540            
Q_RES_0402LF-10K,1%,1/16W,EMPTA CS31002FB26              R612            
Q_RES_0402LF-10K,1%,1/16W,EMPTA CS31002FB26              R630            
Q_RES_0402LF-10K,1%,1/16W,EMPTA CS31002FB26              R641            
Q_RES_0402LF-10K,1%,1/16W,EMPTA CS31002FB26              R643            
Q_RES_0402LF-10K,1%,1/16W,EMPTA CS31002FB26              R701            
Q_RES_0402LF-10K,1%,1/16W,EMPTA CS31002FB26              R702            
Q_RES_0402LF-10K,1%,1/16W,EMPTA CS31002FB26              R703            
Q_RES_0402LF-10K,1%,1/16W,EMPTA CS31002FB26              R704            
Q_RES_0402LF-10K,1%,1/16W,EMPTA CS31002FB26              R705            
Q_RES_0402LF-10K,1%,1/16W,EMPTA CS31002FB26              R706            
Q_RES_0402LF-10K,1%,1/16W,EMPTA CS31002FB26              R707            
Q_RES_0402LF-10K,1%,1/16W,EMPTA CS31002FB26              R708            
Q_RES_0402LF-10K,1%,1/16W,EMPTA CS31002FB26              R711            
Q_RES_0402LF-10K,1%,1/16W,EMPTA CS31002FB26              R713            
Q_RES_0402LF-10K,1%,1/16W,EMPTA CS31002FB26              R715            
Q_RES_0402LF-10K,1%,1/16W,EMPTA CS31002FB26              R717            
Q_RES_0402LF-10K,1%,1/16W,EMPTA CS31002FB26              R728            
Q_RES_0402LF-10K,1%,1/16W,EMPTA CS31002FB26              R732            
Q_RES_0402LF-10K,1%,1/16W,EMPTA CS31002FB26              R781            
Q_RES_0402LF-10K,1%,1/16W,EMPTA CS31002FB26              R785            
Q_RES_0402LF-10K,1%,1/16W,EMPTA CS31002FB26              R997            
Q_RES_0402LF-10K,1%,1/16W,EMPTA CS31002FB26              R1005           
Q_RES_0402LF-10K,1%,1/16W,EMPTA CS31002FB26              R1204           
Q_RES_0402LF-10K,1%,1/16W,EMPTA CS31002FB26              R1223           
Q_RES_0402LF-10K,1%,1/16W,EMPTA CS31002FB26              R1260           
Q_RES_0402LF-10K,1%,1/16W,EMPTA CS31002FB26              R1261           
Q_RES_0402LF-10K,1%,1/16W,EMPTA CS31002FB26              R1262           
Q_RES_0402LF-10K,1%,1/16W,EMPTA CS31002FB26              R1305           
Q_RES_0402LF-10K,1%,1/16W,EMPTA CS31002FB26              R1308           
Q_RES_0402LF-10K,1%,1/16W,EMPTA CS31002FB26              R1312           
Q_RES_0402LF-10K,1%,1/16W,EMPTA CS31002FB26              R1440           
Q_RES_0402LF-10K,1%,1/16W,EMPTA CS31002FB26              R1465           
Q_RES_0402LF-10K,1%,1/16W,EMPTA CS31002FB26              R1483           
Q_RES_0402LF-10K,1%,1/16W,EMPTA CS31002FB26              R1492           
Q_RES_0402LF-10K,1%,1/16W,EMPTA CS31002FB26              R1660           
Q_RES_0402LF-10K,1%,1/16W,EMPTA CS31002FB26              R1673           
Q_RES_0402LF-10K,1%,1/16W,EMPTA CS31002FB26              R1691           
Q_RES_0402LF-10K,1%,1/16W,EMPTA CS31002FB26              R1742           
Q_RES_0402LF-10K,1%,1/16W,EMPTA CS31002FB26              R1749           
Q_RES_0402LF-10K,1%,1/16W,EMPTA CS31002FB26              R1763           
Q_RES_0402LF-10K,1%,1/16W,EMPTA CS31002FB26              R1813           
Q_RES_0402LF-10K,1%,1/16W,EMPTA CS31002FB26              R1841           
Q_RES_0402LF-10K,1%,1/16W,EMPTA CS31002FB26              R1969           
Q_RES_0402LF-10K,1%,1/16W,EMPTA CS31002FB26              R2005           
Q_RES_0402LF-10K,1%,1/16W,EMPTA CS31002FB26              R2006           
Q_RES_0402LF-10K,1%,1/16W,EMPTA CS31002FB26              R2007           
Q_RES_0402LF-10K,1%,1/16W,EMPTA CS31002FB26              R2191           
Q_RES_0402LF-10K,1%,1/16W,EMPTA CS31002FB26              R2195           
Q_RES_0402LF-10K,1%,1/16W,EMPTA CS31002FB26              R2330           
Q_RES_0402LF-10K,1%,1/16W,EMPTA CS31002FB26              R2338           
Q_RES_0402LF-10K,1%,1/16W,EMPTA CS31002FB26              R2367           
Q_RES_0402LF-10K,1%,1/16W,EMPTA CS31002FB26              R2384           

----------------

Q_RES_0402LF-10K,1%,1/16W,EMPTB CS31002FB08              PR400           
Q_RES_0402LF-10K,1%,1/16W,EMPTB CS31002FB08              PR435           
Q_RES_0402LF-10K,1%,1/16W,EMPTB CS31002FB08              PR436           
Q_RES_0402LF-10K,1%,1/16W,EMPTB CS31002FB08              PR634           
Q_RES_0402LF-10K,1%,1/16W,EMPTB CS31002FB08              PR637           
Q_RES_0402LF-10K,1%,1/16W,EMPTB CS31002FB08              PR665           
Q_RES_0402LF-10K,1%,1/16W,EMPTB CS31002FB08              PR667           
Q_RES_0402LF-10K,1%,1/16W,EMPTB CS31002FB08              PR705           

----------------

Q_RES_0402LF-10K,5%,1/16W,CHIPA CS31002JB28              PR73            
Q_RES_0402LF-10K,5%,1/16W,CHIPA CS31002JB28              PR90            
Q_RES_0402LF-10K,5%,1/16W,CHIPA CS31002JB28              R392            
Q_RES_0402LF-10K,5%,1/16W,CHIPA CS31002JB28              R1575           
Q_RES_0402LF-10K,5%,1/16W,CHIPA CS31002JB28              R1576           
Q_RES_0402LF-10K,5%,1/16W,CHIPA CS31002JB28              R1579           
Q_RES_0402LF-10K,5%,1/16W,CHIPA CS31002JB28              R1580           
Q_RES_0402LF-10K,5%,1/16W,CHIPA CS31002JB28              R1642           
Q_RES_0402LF-10K,5%,1/16W,CHIPA CS31002JB28              R1655           
Q_RES_0402LF-10K,5%,1/16W,CHIPA CS31002JB28              R1682           
Q_RES_0402LF-10K,5%,1/16W,CHIPA CS31002JB28              R1929           
Q_RES_0402LF-10K,5%,1/16W,CHIPA CS31002JB28              R1930           
Q_RES_0402LF-10K,5%,1/16W,CHIPA CS31002JB28              R2140           
Q_RES_0402LF-10K,5%,1/16W,CHIPA CS31002JB28              R2158           
Q_RES_0402LF-10K,5%,1/16W,CHIPA CS31002JB28              R2170           
Q_RES_0402LF-10K,5%,1/16W,CHIPA CS31002JB28              R2173           
Q_RES_0402LF-10K,5%,1/16W,CHIPA CS31002JB28              R2174           

----------------

Q_RES_0402LF-10K,5%,1/16W,EMPTA CS31002JB28              R85             
Q_RES_0402LF-10K,5%,1/16W,EMPTA CS31002JB28              R86             
Q_RES_0402LF-10K,5%,1/16W,EMPTA CS31002JB28              R1584           
Q_RES_0402LF-10K,5%,1/16W,EMPTA CS31002JB28              R1586           
Q_RES_0402LF-10K,5%,1/16W,EMPTA CS31002JB28              R1588           
Q_RES_0402LF-10K,5%,1/16W,EMPTA CS31002JB28              R1964           
Q_RES_0402LF-10K,5%,1/16W,EMPTA CS31002JB28              R1974           
Q_RES_0402LF-10K,5%,1/16W,EMPTA CS31002JB28              R1984           
Q_RES_0402LF-10K,5%,1/16W,EMPTA CS31002JB28              R2168           

----------------

Q_RES_0402LF-11.8K,1%,1/16W,CHA CS31182FB18              PR91            

----------------

Q_RES_0402LF-113,1%,1/16W,CHIPA CS11132FB01              R496            

----------------

Q_RES_0402LF-12.4K,1%,1/16W,CHA CS31242FB13              PR50            
Q_RES_0402LF-12.4K,1%,1/16W,CHA CS31242FB13              PR51            

----------------

Q_RES_0402LF-120,1%,1/16W,CHIPA CS11202FB11              R757            

----------------

Q_RES_0402LF-120K,1%,1/16W,CHIA CS41202FB17              R1800           
Q_RES_0402LF-120K,1%,1/16W,CHIA CS41202FB17              R2075           
Q_RES_0402LF-120K,1%,1/16W,CHIA CS41202FB17              R2087           

----------------

Q_RES_0402LF-127K,1%,1/16W,CHIA CS41272FB19              R32             
Q_RES_0402LF-127K,1%,1/16W,CHIA CS41272FB19              R40             
Q_RES_0402LF-127K,1%,1/16W,CHIA CS41272FB19              R48             
Q_RES_0402LF-127K,1%,1/16W,CHIA CS41272FB19              R73             

----------------

Q_RES_0402LF-12K,1%,1/16W,EMPTA CS31202FB15              R1497           

----------------

Q_RES_0402LF-15.4K,1%,1/16W,CHA CS31542FB14              R27             
Q_RES_0402LF-15.4K,1%,1/16W,CHA CS31542FB14              R35             
Q_RES_0402LF-15.4K,1%,1/16W,CHA CS31542FB14              R43             
Q_RES_0402LF-15.4K,1%,1/16W,CHA CS31542FB14              R78             

----------------

Q_RES_0402LF-150,1%,1/16W,CHIPA CS11502FB21              PR112           
Q_RES_0402LF-150,1%,1/16W,CHIPA CS11502FB21              PR163           
Q_RES_0402LF-150,1%,1/16W,CHIPA CS11502FB21              PR209           
Q_RES_0402LF-150,1%,1/16W,CHIPA CS11502FB21              PR265           
Q_RES_0402LF-150,1%,1/16W,CHIPA CS11502FB21              PR310           
Q_RES_0402LF-150,1%,1/16W,CHIPA CS11502FB21              PR364           
Q_RES_0402LF-150,1%,1/16W,CHIPA CS11502FB21              R741            
Q_RES_0402LF-150,1%,1/16W,CHIPA CS11502FB21              R743            
Q_RES_0402LF-150,1%,1/16W,CHIPA CS11502FB21              R747            
Q_RES_0402LF-150,1%,1/16W,CHIPA CS11502FB21              R750            
Q_RES_0402LF-150,1%,1/16W,CHIPA CS11502FB21              R751            
Q_RES_0402LF-150,1%,1/16W,CHIPA CS11502FB21              R758            
Q_RES_0402LF-150,1%,1/16W,CHIPA CS11502FB21              R759            
Q_RES_0402LF-150,1%,1/16W,CHIPA CS11502FB21              R1137           
Q_RES_0402LF-150,1%,1/16W,CHIPA CS11502FB21              R1431           
Q_RES_0402LF-150,1%,1/16W,CHIPA CS11502FB21              R1432           
Q_RES_0402LF-150,1%,1/16W,CHIPA CS11502FB21              R1433           

----------------

Q_RES_0402LF-150,5%,1/16W,CHIPA CS11502JB22              R779            

----------------

Q_RES_0402LF-150K,1%,1/16W,CHIA CS41502FB18              PR1330          

----------------

Q_RES_0402LF-15K,1%,1/16W,CHIPA CS31502FB24              PR89            

----------------

Q_RES_0402LF-18.2K,0.1%,1/16W,A CS31822BB00              PR1310          

----------------

Q_RES_0402LF-18.2K,0.1%,1/16W,B CS31822BB00              PR1314          

----------------

Q_RES_0402LF-196K,1%,1/16W,CHIA CS41962FB01              R33             
Q_RES_0402LF-196K,1%,1/16W,CHIA CS41962FB01              R41             
Q_RES_0402LF-196K,1%,1/16W,CHIA CS41962FB01              R72             
Q_RES_0402LF-196K,1%,1/16W,CHIA CS41962FB01              R80             

----------------

Q_RES_0402LF-1K,0.1%,1/16W,CHIA CS21002BB00              R1787           
Q_RES_0402LF-1K,0.1%,1/16W,CHIA CS21002BB00              R1789           

----------------

Q_RES_0402LF-1K,1%,1/16W,CHIP,A CS21002FB24              PR109           
Q_RES_0402LF-1K,1%,1/16W,CHIP,A CS21002FB24              PR117           
Q_RES_0402LF-1K,1%,1/16W,CHIP,A CS21002FB24              PR131           
Q_RES_0402LF-1K,1%,1/16W,CHIP,A CS21002FB24              PR160           
Q_RES_0402LF-1K,1%,1/16W,CHIP,A CS21002FB24              PR169           
Q_RES_0402LF-1K,1%,1/16W,CHIP,A CS21002FB24              PR172           
Q_RES_0402LF-1K,1%,1/16W,CHIP,A CS21002FB24              PR177           
Q_RES_0402LF-1K,1%,1/16W,CHIP,A CS21002FB24              PR206           
Q_RES_0402LF-1K,1%,1/16W,CHIP,A CS21002FB24              PR215           
Q_RES_0402LF-1K,1%,1/16W,CHIP,A CS21002FB24              PR217           
Q_RES_0402LF-1K,1%,1/16W,CHIP,A CS21002FB24              PR223           
Q_RES_0402LF-1K,1%,1/16W,CHIP,A CS21002FB24              PR232           
Q_RES_0402LF-1K,1%,1/16W,CHIP,A CS21002FB24              PR241           
Q_RES_0402LF-1K,1%,1/16W,CHIP,A CS21002FB24              PR243           
Q_RES_0402LF-1K,1%,1/16W,CHIP,A CS21002FB24              PR249           
Q_RES_0402LF-1K,1%,1/16W,CHIP,A CS21002FB24              PR262           
Q_RES_0402LF-1K,1%,1/16W,CHIP,A CS21002FB24              PR270           
Q_RES_0402LF-1K,1%,1/16W,CHIP,A CS21002FB24              PR284           
Q_RES_0402LF-1K,1%,1/16W,CHIP,A CS21002FB24              PR307           
Q_RES_0402LF-1K,1%,1/16W,CHIP,A CS21002FB24              PR335           
Q_RES_0402LF-1K,1%,1/16W,CHIP,A CS21002FB24              PR361           
Q_RES_0402LF-1K,1%,1/16W,CHIP,A CS21002FB24              PR370           
Q_RES_0402LF-1K,1%,1/16W,CHIP,A CS21002FB24              PR372           
Q_RES_0402LF-1K,1%,1/16W,CHIP,A CS21002FB24              PR378           
Q_RES_0402LF-1K,1%,1/16W,CHIP,A CS21002FB24              PR523           
Q_RES_0402LF-1K,1%,1/16W,CHIP,A CS21002FB24              PR524           
Q_RES_0402LF-1K,1%,1/16W,CHIP,A CS21002FB24              PR570           
Q_RES_0402LF-1K,1%,1/16W,CHIP,A CS21002FB24              PR571           
Q_RES_0402LF-1K,1%,1/16W,CHIP,A CS21002FB24              PR836           
Q_RES_0402LF-1K,1%,1/16W,CHIP,A CS21002FB24              R537            
Q_RES_0402LF-1K,1%,1/16W,CHIP,A CS21002FB24              R539            
Q_RES_0402LF-1K,1%,1/16W,CHIP,A CS21002FB24              R587            
Q_RES_0402LF-1K,1%,1/16W,CHIP,A CS21002FB24              R629            
Q_RES_0402LF-1K,1%,1/16W,CHIP,A CS21002FB24              R642            
Q_RES_0402LF-1K,1%,1/16W,CHIP,A CS21002FB24              R644            
Q_RES_0402LF-1K,1%,1/16W,CHIP,A CS21002FB24              R650            
Q_RES_0402LF-1K,1%,1/16W,CHIP,A CS21002FB24              R661            
Q_RES_0402LF-1K,1%,1/16W,CHIP,A CS21002FB24              R678            
Q_RES_0402LF-1K,1%,1/16W,CHIP,A CS21002FB24              R710            
Q_RES_0402LF-1K,1%,1/16W,CHIP,A CS21002FB24              R712            
Q_RES_0402LF-1K,1%,1/16W,CHIP,A CS21002FB24              R714            
Q_RES_0402LF-1K,1%,1/16W,CHIP,A CS21002FB24              R716            
Q_RES_0402LF-1K,1%,1/16W,CHIP,A CS21002FB24              R718            
Q_RES_0402LF-1K,1%,1/16W,CHIP,A CS21002FB24              R729            
Q_RES_0402LF-1K,1%,1/16W,CHIP,A CS21002FB24              R733            
Q_RES_0402LF-1K,1%,1/16W,CHIP,A CS21002FB24              R767            
Q_RES_0402LF-1K,1%,1/16W,CHIP,A CS21002FB24              R768            
Q_RES_0402LF-1K,1%,1/16W,CHIP,A CS21002FB24              R771            
Q_RES_0402LF-1K,1%,1/16W,CHIP,A CS21002FB24              R772            
Q_RES_0402LF-1K,1%,1/16W,CHIP,A CS21002FB24              R773            
Q_RES_0402LF-1K,1%,1/16W,CHIP,A CS21002FB24              R778            
Q_RES_0402LF-1K,1%,1/16W,CHIP,A CS21002FB24              R782            
Q_RES_0402LF-1K,1%,1/16W,CHIP,A CS21002FB24              R786            
Q_RES_0402LF-1K,1%,1/16W,CHIP,A CS21002FB24              R940            
Q_RES_0402LF-1K,1%,1/16W,CHIP,A CS21002FB24              R941            
Q_RES_0402LF-1K,1%,1/16W,CHIP,A CS21002FB24              R942            
Q_RES_0402LF-1K,1%,1/16W,CHIP,A CS21002FB24              R943            
Q_RES_0402LF-1K,1%,1/16W,CHIP,A CS21002FB24              R944            
Q_RES_0402LF-1K,1%,1/16W,CHIP,A CS21002FB24              R945            
Q_RES_0402LF-1K,1%,1/16W,CHIP,A CS21002FB24              R946            
Q_RES_0402LF-1K,1%,1/16W,CHIP,A CS21002FB24              R947            
Q_RES_0402LF-1K,1%,1/16W,CHIP,A CS21002FB24              R965            
Q_RES_0402LF-1K,1%,1/16W,CHIP,A CS21002FB24              R966            
Q_RES_0402LF-1K,1%,1/16W,CHIP,A CS21002FB24              R967            
Q_RES_0402LF-1K,1%,1/16W,CHIP,A CS21002FB24              R968            
Q_RES_0402LF-1K,1%,1/16W,CHIP,A CS21002FB24              R1004           
Q_RES_0402LF-1K,1%,1/16W,CHIP,A CS21002FB24              R1026           
Q_RES_0402LF-1K,1%,1/16W,CHIP,A CS21002FB24              R1146           
Q_RES_0402LF-1K,1%,1/16W,CHIP,A CS21002FB24              R1203           
Q_RES_0402LF-1K,1%,1/16W,CHIP,A CS21002FB24              R1221           
Q_RES_0402LF-1K,1%,1/16W,CHIP,A CS21002FB24              R1226           
Q_RES_0402LF-1K,1%,1/16W,CHIP,A CS21002FB24              R1253           
Q_RES_0402LF-1K,1%,1/16W,CHIP,A CS21002FB24              R1255           
Q_RES_0402LF-1K,1%,1/16W,CHIP,A CS21002FB24              R1267           
Q_RES_0402LF-1K,1%,1/16W,CHIP,A CS21002FB24              R1317           
Q_RES_0402LF-1K,1%,1/16W,CHIP,A CS21002FB24              R1320           
Q_RES_0402LF-1K,1%,1/16W,CHIP,A CS21002FB24              R1324           
Q_RES_0402LF-1K,1%,1/16W,CHIP,A CS21002FB24              R1325           
Q_RES_0402LF-1K,1%,1/16W,CHIP,A CS21002FB24              R1333           
Q_RES_0402LF-1K,1%,1/16W,CHIP,A CS21002FB24              R1334           
Q_RES_0402LF-1K,1%,1/16W,CHIP,A CS21002FB24              R1335           
Q_RES_0402LF-1K,1%,1/16W,CHIP,A CS21002FB24              R1346           
Q_RES_0402LF-1K,1%,1/16W,CHIP,A CS21002FB24              R1347           
Q_RES_0402LF-1K,1%,1/16W,CHIP,A CS21002FB24              R1356           
Q_RES_0402LF-1K,1%,1/16W,CHIP,A CS21002FB24              R1365           
Q_RES_0402LF-1K,1%,1/16W,CHIP,A CS21002FB24              R1368           
Q_RES_0402LF-1K,1%,1/16W,CHIP,A CS21002FB24              R1369           
Q_RES_0402LF-1K,1%,1/16W,CHIP,A CS21002FB24              R1371           
Q_RES_0402LF-1K,1%,1/16W,CHIP,A CS21002FB24              R1372           
Q_RES_0402LF-1K,1%,1/16W,CHIP,A CS21002FB24              R1373           
Q_RES_0402LF-1K,1%,1/16W,CHIP,A CS21002FB24              R1374           
Q_RES_0402LF-1K,1%,1/16W,CHIP,A CS21002FB24              R1376           
Q_RES_0402LF-1K,1%,1/16W,CHIP,A CS21002FB24              R1377           
Q_RES_0402LF-1K,1%,1/16W,CHIP,A CS21002FB24              R1380           
Q_RES_0402LF-1K,1%,1/16W,CHIP,A CS21002FB24              R1381           
Q_RES_0402LF-1K,1%,1/16W,CHIP,A CS21002FB24              R1382           
Q_RES_0402LF-1K,1%,1/16W,CHIP,A CS21002FB24              R1383           
Q_RES_0402LF-1K,1%,1/16W,CHIP,A CS21002FB24              R1441           
Q_RES_0402LF-1K,1%,1/16W,CHIP,A CS21002FB24              R1462           
Q_RES_0402LF-1K,1%,1/16W,CHIP,A CS21002FB24              R1473           
Q_RES_0402LF-1K,1%,1/16W,CHIP,A CS21002FB24              R1474           
Q_RES_0402LF-1K,1%,1/16W,CHIP,A CS21002FB24              R1476           
Q_RES_0402LF-1K,1%,1/16W,CHIP,A CS21002FB24              R1491           
Q_RES_0402LF-1K,1%,1/16W,CHIP,A CS21002FB24              R1494           
Q_RES_0402LF-1K,1%,1/16W,CHIP,A CS21002FB24              R1499           
Q_RES_0402LF-1K,1%,1/16W,CHIP,A CS21002FB24              R1527           
Q_RES_0402LF-1K,1%,1/16W,CHIP,A CS21002FB24              R1605           
Q_RES_0402LF-1K,1%,1/16W,CHIP,A CS21002FB24              R1712           
Q_RES_0402LF-1K,1%,1/16W,CHIP,A CS21002FB24              R1713           
Q_RES_0402LF-1K,1%,1/16W,CHIP,A CS21002FB24              R1741           
Q_RES_0402LF-1K,1%,1/16W,CHIP,A CS21002FB24              R1750           
Q_RES_0402LF-1K,1%,1/16W,CHIP,A CS21002FB24              R1814           
Q_RES_0402LF-1K,1%,1/16W,CHIP,A CS21002FB24              R1823           
Q_RES_0402LF-1K,1%,1/16W,CHIP,A CS21002FB24              R2133           
Q_RES_0402LF-1K,1%,1/16W,CHIP,A CS21002FB24              R2192           
Q_RES_0402LF-1K,1%,1/16W,CHIP,A CS21002FB24              R2196           

----------------

Q_RES_0402LF-1K,1%,1/16W,EMPTYA CS21002FB24              PR123           
Q_RES_0402LF-1K,1%,1/16W,EMPTYA CS21002FB24              PR166           
Q_RES_0402LF-1K,1%,1/16W,EMPTYA CS21002FB24              PR214           
Q_RES_0402LF-1K,1%,1/16W,EMPTYA CS21002FB24              PR218           
Q_RES_0402LF-1K,1%,1/16W,EMPTYA CS21002FB24              PR276           
Q_RES_0402LF-1K,1%,1/16W,EMPTYA CS21002FB24              PR313           
Q_RES_0402LF-1K,1%,1/16W,EMPTYA CS21002FB24              PR369           
Q_RES_0402LF-1K,1%,1/16W,EMPTYA CS21002FB24              PR373           
Q_RES_0402LF-1K,1%,1/16W,EMPTYA CS21002FB24              R241            
Q_RES_0402LF-1K,1%,1/16W,EMPTYA CS21002FB24              R242            
Q_RES_0402LF-1K,1%,1/16W,EMPTYA CS21002FB24              R331            
Q_RES_0402LF-1K,1%,1/16W,EMPTYA CS21002FB24              R333            
Q_RES_0402LF-1K,1%,1/16W,EMPTYA CS21002FB24              R335            
Q_RES_0402LF-1K,1%,1/16W,EMPTYA CS21002FB24              R420            
Q_RES_0402LF-1K,1%,1/16W,EMPTYA CS21002FB24              R422            
Q_RES_0402LF-1K,1%,1/16W,EMPTYA CS21002FB24              R487            
Q_RES_0402LF-1K,1%,1/16W,EMPTYA CS21002FB24              R625            
Q_RES_0402LF-1K,1%,1/16W,EMPTYA CS21002FB24              R627            
Q_RES_0402LF-1K,1%,1/16W,EMPTYA CS21002FB24              R646            
Q_RES_0402LF-1K,1%,1/16W,EMPTYA CS21002FB24              R720            
Q_RES_0402LF-1K,1%,1/16W,EMPTYA CS21002FB24              R722            
Q_RES_0402LF-1K,1%,1/16W,EMPTYA CS21002FB24              R731            
Q_RES_0402LF-1K,1%,1/16W,EMPTYA CS21002FB24              R736            
Q_RES_0402LF-1K,1%,1/16W,EMPTYA CS21002FB24              R766            
Q_RES_0402LF-1K,1%,1/16W,EMPTYA CS21002FB24              R784            
Q_RES_0402LF-1K,1%,1/16W,EMPTYA CS21002FB24              R819            
Q_RES_0402LF-1K,1%,1/16W,EMPTYA CS21002FB24              R820            
Q_RES_0402LF-1K,1%,1/16W,EMPTYA CS21002FB24              R821            
Q_RES_0402LF-1K,1%,1/16W,EMPTYA CS21002FB24              R822            
Q_RES_0402LF-1K,1%,1/16W,EMPTYA CS21002FB24              R839            
Q_RES_0402LF-1K,1%,1/16W,EMPTYA CS21002FB24              R840            
Q_RES_0402LF-1K,1%,1/16W,EMPTYA CS21002FB24              R841            
Q_RES_0402LF-1K,1%,1/16W,EMPTYA CS21002FB24              R842            
Q_RES_0402LF-1K,1%,1/16W,EMPTYA CS21002FB24              R1008           
Q_RES_0402LF-1K,1%,1/16W,EMPTYA CS21002FB24              R1009           
Q_RES_0402LF-1K,1%,1/16W,EMPTYA CS21002FB24              R1220           
Q_RES_0402LF-1K,1%,1/16W,EMPTYA CS21002FB24              R1390           
Q_RES_0402LF-1K,1%,1/16W,EMPTYA CS21002FB24              R1475           
Q_RES_0402LF-1K,1%,1/16W,EMPTYA CS21002FB24              R1477           
Q_RES_0402LF-1K,1%,1/16W,EMPTYA CS21002FB24              R1484           
Q_RES_0402LF-1K,1%,1/16W,EMPTYA CS21002FB24              R1493           
Q_RES_0402LF-1K,1%,1/16W,EMPTYA CS21002FB24              R1498           
Q_RES_0402LF-1K,1%,1/16W,EMPTYA CS21002FB24              R1676           
Q_RES_0402LF-1K,1%,1/16W,EMPTYA CS21002FB24              R1764           
Q_RES_0402LF-1K,1%,1/16W,EMPTYA CS21002FB24              R1790           
Q_RES_0402LF-1K,1%,1/16W,EMPTYA CS21002FB24              R2194           

----------------

Q_RES_0402LF-1K,5%,1/16W,CHIP,A CS21002JB34              R367            
Q_RES_0402LF-1K,5%,1/16W,CHIP,A CS21002JB34              R369            
Q_RES_0402LF-1K,5%,1/16W,CHIP,A CS21002JB34              R379            
Q_RES_0402LF-1K,5%,1/16W,CHIP,A CS21002JB34              R611            
Q_RES_0402LF-1K,5%,1/16W,CHIP,A CS21002JB34              R615            
Q_RES_0402LF-1K,5%,1/16W,CHIP,A CS21002JB34              R622            
Q_RES_0402LF-1K,5%,1/16W,CHIP,A CS21002JB34              R1124           
Q_RES_0402LF-1K,5%,1/16W,CHIP,A CS21002JB34              R1126           
Q_RES_0402LF-1K,5%,1/16W,CHIP,A CS21002JB34              R1128           
Q_RES_0402LF-1K,5%,1/16W,CHIP,A CS21002JB34              R1129           
Q_RES_0402LF-1K,5%,1/16W,CHIP,A CS21002JB34              R1142           
Q_RES_0402LF-1K,5%,1/16W,CHIP,A CS21002JB34              R1654           
Q_RES_0402LF-1K,5%,1/16W,CHIP,A CS21002JB34              R2090           
Q_RES_0402LF-1K,5%,1/16W,CHIP,A CS21002JB34              R2092           
Q_RES_0402LF-1K,5%,1/16W,CHIP,A CS21002JB34              R2094           
Q_RES_0402LF-1K,5%,1/16W,CHIP,A CS21002JB34              R2096           
Q_RES_0402LF-1K,5%,1/16W,CHIP,A CS21002JB34              R2098           
Q_RES_0402LF-1K,5%,1/16W,CHIP,A CS21002JB34              R2100           

----------------

Q_RES_0402LF-1K,5%,1/16W,EMPTYA CS21002JB34              R87             
Q_RES_0402LF-1K,5%,1/16W,EMPTYA CS21002JB34              R371            
Q_RES_0402LF-1K,5%,1/16W,EMPTYA CS21002JB34              R374            
Q_RES_0402LF-1K,5%,1/16W,EMPTYA CS21002JB34              R378            
Q_RES_0402LF-1K,5%,1/16W,EMPTYA CS21002JB34              R380            
Q_RES_0402LF-1K,5%,1/16W,EMPTYA CS21002JB34              R382            
Q_RES_0402LF-1K,5%,1/16W,EMPTYA CS21002JB34              R607            
Q_RES_0402LF-1K,5%,1/16W,EMPTYA CS21002JB34              R609            
Q_RES_0402LF-1K,5%,1/16W,EMPTYA CS21002JB34              R614            
Q_RES_0402LF-1K,5%,1/16W,EMPTYA CS21002JB34              R617            
Q_RES_0402LF-1K,5%,1/16W,EMPTYA CS21002JB34              R621            
Q_RES_0402LF-1K,5%,1/16W,EMPTYA CS21002JB34              R623            
Q_RES_0402LF-1K,5%,1/16W,EMPTYA CS21002JB34              R920            
Q_RES_0402LF-1K,5%,1/16W,EMPTYA CS21002JB34              R1123           
Q_RES_0402LF-1K,5%,1/16W,EMPTYA CS21002JB34              R1125           
Q_RES_0402LF-1K,5%,1/16W,EMPTYA CS21002JB34              R1127           
Q_RES_0402LF-1K,5%,1/16W,EMPTYA CS21002JB34              R1132           
Q_RES_0402LF-1K,5%,1/16W,EMPTYA CS21002JB34              R1197           
Q_RES_0402LF-1K,5%,1/16W,EMPTYA CS21002JB34              R1298           
Q_RES_0402LF-1K,5%,1/16W,EMPTYA CS21002JB34              R1315           
Q_RES_0402LF-1K,5%,1/16W,EMPTYA CS21002JB34              R1810           
Q_RES_0402LF-1K,5%,1/16W,EMPTYA CS21002JB34              R1850           
Q_RES_0402LF-1K,5%,1/16W,EMPTYA CS21002JB34              R2089           
Q_RES_0402LF-1K,5%,1/16W,EMPTYA CS21002JB34              R2091           
Q_RES_0402LF-1K,5%,1/16W,EMPTYA CS21002JB34              R2093           
Q_RES_0402LF-1K,5%,1/16W,EMPTYA CS21002JB34              R2095           
Q_RES_0402LF-1K,5%,1/16W,EMPTYA CS21002JB34              R2097           
Q_RES_0402LF-1K,5%,1/16W,EMPTYA CS21002JB34              R2099           

----------------

Q_RES_0402LF-2.2,1%,1/16W,CHIPA CS-2202FB00              PR97            
Q_RES_0402LF-2.2,1%,1/16W,CHIPA CS-2202FB00              PR101           
Q_RES_0402LF-2.2,1%,1/16W,CHIPA CS-2202FB00              PR102           
Q_RES_0402LF-2.2,1%,1/16W,CHIPA CS-2202FB00              PR134           
Q_RES_0402LF-2.2,1%,1/16W,CHIPA CS-2202FB00              PR135           
Q_RES_0402LF-2.2,1%,1/16W,CHIPA CS-2202FB00              PR140           
Q_RES_0402LF-2.2,1%,1/16W,CHIPA CS-2202FB00              PR141           
Q_RES_0402LF-2.2,1%,1/16W,CHIPA CS-2202FB00              PR146           
Q_RES_0402LF-2.2,1%,1/16W,CHIPA CS-2202FB00              PR147           
Q_RES_0402LF-2.2,1%,1/16W,CHIPA CS-2202FB00              PR152           
Q_RES_0402LF-2.2,1%,1/16W,CHIPA CS-2202FB00              PR153           
Q_RES_0402LF-2.2,1%,1/16W,CHIPA CS-2202FB00              PR200           
Q_RES_0402LF-2.2,1%,1/16W,CHIPA CS-2202FB00              PR226           
Q_RES_0402LF-2.2,1%,1/16W,CHIPA CS-2202FB00              PR227           
Q_RES_0402LF-2.2,1%,1/16W,CHIPA CS-2202FB00              PR250           
Q_RES_0402LF-2.2,1%,1/16W,CHIPA CS-2202FB00              PR254           
Q_RES_0402LF-2.2,1%,1/16W,CHIPA CS-2202FB00              PR255           
Q_RES_0402LF-2.2,1%,1/16W,CHIPA CS-2202FB00              PR287           
Q_RES_0402LF-2.2,1%,1/16W,CHIPA CS-2202FB00              PR288           
Q_RES_0402LF-2.2,1%,1/16W,CHIPA CS-2202FB00              PR293           
Q_RES_0402LF-2.2,1%,1/16W,CHIPA CS-2202FB00              PR294           
Q_RES_0402LF-2.2,1%,1/16W,CHIPA CS-2202FB00              PR299           
Q_RES_0402LF-2.2,1%,1/16W,CHIPA CS-2202FB00              PR300           
Q_RES_0402LF-2.2,1%,1/16W,CHIPA CS-2202FB00              PR327           
Q_RES_0402LF-2.2,1%,1/16W,CHIPA CS-2202FB00              PR328           
Q_RES_0402LF-2.2,1%,1/16W,CHIPA CS-2202FB00              PR355           
Q_RES_0402LF-2.2,1%,1/16W,CHIPA CS-2202FB00              PR356           
Q_RES_0402LF-2.2,1%,1/16W,CHIPA CS-2202FB00              PR380           
Q_RES_0402LF-2.2,1%,1/16W,CHIPA CS-2202FB00              PR1306          
Q_RES_0402LF-2.2,1%,1/16W,CHIPA CS-2202FB00              PR1307          

----------------

Q_RES_0402LF-2.2,1%,1/16W,EMPTA CS-2202FB00              PR1299          
Q_RES_0402LF-2.2,1%,1/16W,EMPTA CS-2202FB00              PR1300          

----------------

Q_RES_0402LF-2.21K    ,1%  ,1/A CS22212FB11              R1271           

----------------

Q_RES_0402LF-2.2K ,5%,1/16W,CHA CS22202JB18              R592            
Q_RES_0402LF-2.2K ,5%,1/16W,CHA CS22202JB18              R601            
Q_RES_0402LF-2.2K ,5%,1/16W,CHA CS22202JB18              R606            
Q_RES_0402LF-2.2K ,5%,1/16W,CHA CS22202JB18              R649            
Q_RES_0402LF-2.2K ,5%,1/16W,CHA CS22202JB18              R651            
Q_RES_0402LF-2.2K ,5%,1/16W,CHA CS22202JB18              R652            
Q_RES_0402LF-2.2K ,5%,1/16W,CHA CS22202JB18              R653            
Q_RES_0402LF-2.2K ,5%,1/16W,CHA CS22202JB18              R654            
Q_RES_0402LF-2.2K ,5%,1/16W,CHA CS22202JB18              R655            
Q_RES_0402LF-2.2K ,5%,1/16W,CHA CS22202JB18              R656            
Q_RES_0402LF-2.2K ,5%,1/16W,CHA CS22202JB18              R791            
Q_RES_0402LF-2.2K ,5%,1/16W,CHA CS22202JB18              R792            
Q_RES_0402LF-2.2K ,5%,1/16W,CHA CS22202JB18              R793            
Q_RES_0402LF-2.2K ,5%,1/16W,CHA CS22202JB18              R794            
Q_RES_0402LF-2.2K ,5%,1/16W,CHA CS22202JB18              R795            
Q_RES_0402LF-2.2K ,5%,1/16W,CHA CS22202JB18              R796            
Q_RES_0402LF-2.2K ,5%,1/16W,CHA CS22202JB18              R797            
Q_RES_0402LF-2.2K ,5%,1/16W,CHA CS22202JB18              R798            
Q_RES_0402LF-2.2K ,5%,1/16W,CHA CS22202JB18              R914            
Q_RES_0402LF-2.2K ,5%,1/16W,CHA CS22202JB18              R1089           
Q_RES_0402LF-2.2K ,5%,1/16W,CHA CS22202JB18              R1090           
Q_RES_0402LF-2.2K ,5%,1/16W,CHA CS22202JB18              R1091           
Q_RES_0402LF-2.2K ,5%,1/16W,CHA CS22202JB18              R1092           
Q_RES_0402LF-2.2K ,5%,1/16W,CHA CS22202JB18              R1314           
Q_RES_0402LF-2.2K ,5%,1/16W,CHA CS22202JB18              R1336           
Q_RES_0402LF-2.2K ,5%,1/16W,CHA CS22202JB18              R1460           
Q_RES_0402LF-2.2K ,5%,1/16W,CHA CS22202JB18              R2051           
Q_RES_0402LF-2.2K ,5%,1/16W,CHA CS22202JB18              R2052           
Q_RES_0402LF-2.2K ,5%,1/16W,CHA CS22202JB18              R2053           
Q_RES_0402LF-2.2K ,5%,1/16W,CHA CS22202JB18              R2054           
Q_RES_0402LF-2.2K ,5%,1/16W,CHA CS22202JB18              R2055           
Q_RES_0402LF-2.2K ,5%,1/16W,CHA CS22202JB18              R2056           
Q_RES_0402LF-2.2K ,5%,1/16W,CHA CS22202JB18              R2057           
Q_RES_0402LF-2.2K ,5%,1/16W,CHA CS22202JB18              R2058           
Q_RES_0402LF-2.2K ,5%,1/16W,CHA CS22202JB18              R2198           
Q_RES_0402LF-2.2K ,5%,1/16W,CHA CS22202JB18              R2199           
Q_RES_0402LF-2.2K ,5%,1/16W,CHA CS22202JB18              R2200           
Q_RES_0402LF-2.2K ,5%,1/16W,CHA CS22202JB18              R2201           
Q_RES_0402LF-2.2K ,5%,1/16W,CHA CS22202JB18              R2202           
Q_RES_0402LF-2.2K ,5%,1/16W,CHA CS22202JB18              R2203           
Q_RES_0402LF-2.2K ,5%,1/16W,CHA CS22202JB18              R2204           
Q_RES_0402LF-2.2K ,5%,1/16W,CHA CS22202JB18              R2205           
Q_RES_0402LF-2.2K ,5%,1/16W,CHA CS22202JB18              R2206           
Q_RES_0402LF-2.2K ,5%,1/16W,CHA CS22202JB18              R2207           
Q_RES_0402LF-2.2K ,5%,1/16W,CHA CS22202JB18              R2212           
Q_RES_0402LF-2.2K ,5%,1/16W,CHA CS22202JB18              R2213           

----------------

Q_RES_0402LF-2.2K ,5%,1/16W,EMA CS22202JB18              R657            
Q_RES_0402LF-2.2K ,5%,1/16W,EMA CS22202JB18              R658            
Q_RES_0402LF-2.2K ,5%,1/16W,EMA CS22202JB18              R1065           
Q_RES_0402LF-2.2K ,5%,1/16W,EMA CS22202JB18              R1066           
Q_RES_0402LF-2.2K ,5%,1/16W,EMA CS22202JB18              R1067           
Q_RES_0402LF-2.2K ,5%,1/16W,EMA CS22202JB18              R1068           
Q_RES_0402LF-2.2K ,5%,1/16W,EMA CS22202JB18              R1069           
Q_RES_0402LF-2.2K ,5%,1/16W,EMA CS22202JB18              R1070           
Q_RES_0402LF-2.2K ,5%,1/16W,EMA CS22202JB18              R1071           
Q_RES_0402LF-2.2K ,5%,1/16W,EMA CS22202JB18              R1072           

----------------

Q_RES_0402LF-2.49K,1%,1/16W,CHA CS22492FB22              R1675           

----------------

Q_RES_0402LF-2.4K,1%,1/16W,CHIA CS22402FB00              R2076           
Q_RES_0402LF-2.4K,1%,1/16W,CHIA CS22402FB00              R2088           
Q_RES_0402LF-2.4K,1%,1/16W,CHIA CS22402FB00              R2141           
Q_RES_0402LF-2.4K,1%,1/16W,CHIA CS22402FB00              R2142           

----------------

Q_RES_0402LF-200,1%,1/16W,CHIPA CS12002FB25              R4              
Q_RES_0402LF-200,1%,1/16W,CHIPA CS12002FB25              R14             
Q_RES_0402LF-200,1%,1/16W,CHIPA CS12002FB25              R17             
Q_RES_0402LF-200,1%,1/16W,CHIPA CS12002FB25              R57             
Q_RES_0402LF-200,1%,1/16W,CHIPA CS12002FB25              R60             
Q_RES_0402LF-200,1%,1/16W,CHIPA CS12002FB25              R64             
Q_RES_0402LF-200,1%,1/16W,CHIPA CS12002FB25              R497            

----------------

Q_RES_0402LF-200,1%,1/16W,EMPTA CS12002FB25              R1485           
Q_RES_0402LF-200,1%,1/16W,EMPTA CS12002FB25              R1486           

----------------

Q_RES_0402LF-200K,1%,1/16W,CHIA CS42002FB12              R1791           

----------------

Q_RES_0402LF-20K,1%,1/16W,CHIPA CS32002FB29              R462            
Q_RES_0402LF-20K,1%,1/16W,CHIPA CS32002FB29              R1202           
Q_RES_0402LF-20K,1%,1/16W,CHIPA CS32002FB29              R1809           

----------------

Q_RES_0402LF-20K,5%,1/16W,CHIPA CS32002JB12              R1340           
Q_RES_0402LF-20K,5%,1/16W,CHIPA CS32002JB12              R1698           
Q_RES_0402LF-20K,5%,1/16W,CHIPA CS32002JB12              R1962           

----------------

Q_RES_0402LF-20K,5%,1/16W,EMPTA CS32002JB12              R502            

----------------

Q_RES_0402LF-21.5K,1%,1/16W,CHA CS32152FB17              PR834           

----------------

Q_RES_0402LF-22,1%,1/16W,CHIP,A CS02202FB12              R1290           
Q_RES_0402LF-22,1%,1/16W,CHIP,A CS02202FB12              R1291           
Q_RES_0402LF-22,1%,1/16W,CHIP,A CS02202FB12              R1292           
Q_RES_0402LF-22,1%,1/16W,CHIP,A CS02202FB12              R1293           
Q_RES_0402LF-22,1%,1/16W,CHIP,A CS02202FB12              R1294           
Q_RES_0402LF-22,1%,1/16W,CHIP,A CS02202FB12              R1295           
Q_RES_0402LF-22,1%,1/16W,CHIP,A CS02202FB12              R1296           

----------------

Q_RES_0402LF-23.2K,1%,1/16W,CHA CS32322FB11              R28             
Q_RES_0402LF-23.2K,1%,1/16W,CHA CS32322FB11              R36             
Q_RES_0402LF-23.2K,1%,1/16W,CHA CS32322FB11              R44             
Q_RES_0402LF-23.2K,1%,1/16W,CHA CS32322FB11              R77             

----------------

Q_RES_0402LF-240,1%,1/16W,CHIPA CS12402FB03              R252            
Q_RES_0402LF-240,1%,1/16W,CHIPA CS12402FB03              R253            
Q_RES_0402LF-240,1%,1/16W,CHIPA CS12402FB03              R254            
Q_RES_0402LF-240,1%,1/16W,CHIPA CS12402FB03              R258            
Q_RES_0402LF-240,1%,1/16W,CHIPA CS12402FB03              R259            
Q_RES_0402LF-240,1%,1/16W,CHIPA CS12402FB03              R260            
Q_RES_0402LF-240,1%,1/16W,CHIPA CS12402FB03              R265            
Q_RES_0402LF-240,1%,1/16W,CHIPA CS12402FB03              R275            
Q_RES_0402LF-240,1%,1/16W,CHIPA CS12402FB03              R277            
Q_RES_0402LF-240,1%,1/16W,CHIPA CS12402FB03              R282            
Q_RES_0402LF-240,1%,1/16W,CHIPA CS12402FB03              R288            
Q_RES_0402LF-240,1%,1/16W,CHIPA CS12402FB03              R289            
Q_RES_0402LF-240,1%,1/16W,CHIPA CS12402FB03              R290            
Q_RES_0402LF-240,1%,1/16W,CHIPA CS12402FB03              R292            
Q_RES_0402LF-240,1%,1/16W,CHIPA CS12402FB03              R293            
Q_RES_0402LF-240,1%,1/16W,CHIPA CS12402FB03              R910            
Q_RES_0402LF-240,1%,1/16W,CHIPA CS12402FB03              R911            
Q_RES_0402LF-240,1%,1/16W,CHIPA CS12402FB03              R963            
Q_RES_0402LF-240,1%,1/16W,CHIPA CS12402FB03              R964            
Q_RES_0402LF-240,1%,1/16W,CHIPA CS12402FB03              R969            
Q_RES_0402LF-240,1%,1/16W,CHIPA CS12402FB03              R970            
Q_RES_0402LF-240,1%,1/16W,CHIPA CS12402FB03              R971            
Q_RES_0402LF-240,1%,1/16W,CHIPA CS12402FB03              R972            

----------------

Q_RES_0402LF-240,1%,1/16W,EMPTA CS12402FB03              R90             
Q_RES_0402LF-240,1%,1/16W,EMPTA CS12402FB03              R91             
Q_RES_0402LF-240,1%,1/16W,EMPTA CS12402FB03              R92             
Q_RES_0402LF-240,1%,1/16W,EMPTA CS12402FB03              R93             
Q_RES_0402LF-240,1%,1/16W,EMPTA CS12402FB03              R94             
Q_RES_0402LF-240,1%,1/16W,EMPTA CS12402FB03              R95             
Q_RES_0402LF-240,1%,1/16W,EMPTA CS12402FB03              R96             
Q_RES_0402LF-240,1%,1/16W,EMPTA CS12402FB03              R97             
Q_RES_0402LF-240,1%,1/16W,EMPTA CS12402FB03              R249            
Q_RES_0402LF-240,1%,1/16W,EMPTA CS12402FB03              R250            
Q_RES_0402LF-240,1%,1/16W,EMPTA CS12402FB03              R251            
Q_RES_0402LF-240,1%,1/16W,EMPTA CS12402FB03              R255            
Q_RES_0402LF-240,1%,1/16W,EMPTA CS12402FB03              R256            
Q_RES_0402LF-240,1%,1/16W,EMPTA CS12402FB03              R257            
Q_RES_0402LF-240,1%,1/16W,EMPTA CS12402FB03              R261            
Q_RES_0402LF-240,1%,1/16W,EMPTA CS12402FB03              R262            
Q_RES_0402LF-240,1%,1/16W,EMPTA CS12402FB03              R263            
Q_RES_0402LF-240,1%,1/16W,EMPTA CS12402FB03              R264            
Q_RES_0402LF-240,1%,1/16W,EMPTA CS12402FB03              R266            
Q_RES_0402LF-240,1%,1/16W,EMPTA CS12402FB03              R267            
Q_RES_0402LF-240,1%,1/16W,EMPTA CS12402FB03              R268            
Q_RES_0402LF-240,1%,1/16W,EMPTA CS12402FB03              R276            
Q_RES_0402LF-240,1%,1/16W,EMPTA CS12402FB03              R278            
Q_RES_0402LF-240,1%,1/16W,EMPTA CS12402FB03              R279            
Q_RES_0402LF-240,1%,1/16W,EMPTA CS12402FB03              R280            
Q_RES_0402LF-240,1%,1/16W,EMPTA CS12402FB03              R281            
Q_RES_0402LF-240,1%,1/16W,EMPTA CS12402FB03              R291            
Q_RES_0402LF-240,1%,1/16W,EMPTA CS12402FB03              R294            
Q_RES_0402LF-240,1%,1/16W,EMPTA CS12402FB03              R295            
Q_RES_0402LF-240,1%,1/16W,EMPTA CS12402FB03              R1229           
Q_RES_0402LF-240,1%,1/16W,EMPTA CS12402FB03              R1230           
Q_RES_0402LF-240,1%,1/16W,EMPTA CS12402FB03              R1232           
Q_RES_0402LF-240,1%,1/16W,EMPTA CS12402FB03              R1233           
Q_RES_0402LF-240,1%,1/16W,EMPTA CS12402FB03              R1234           
Q_RES_0402LF-240,1%,1/16W,EMPTA CS12402FB03              R1235           
Q_RES_0402LF-240,1%,1/16W,EMPTA CS12402FB03              R1236           
Q_RES_0402LF-240,1%,1/16W,EMPTA CS12402FB03              R1237           
Q_RES_0402LF-240,1%,1/16W,EMPTA CS12402FB03              R1238           
Q_RES_0402LF-240,1%,1/16W,EMPTA CS12402FB03              R1239           
Q_RES_0402LF-240,1%,1/16W,EMPTA CS12402FB03              R1270           
Q_RES_0402LF-240,1%,1/16W,EMPTA CS12402FB03              R1391           
Q_RES_0402LF-240,1%,1/16W,EMPTA CS12402FB03              R1392           
Q_RES_0402LF-240,1%,1/16W,EMPTA CS12402FB03              R1393           
Q_RES_0402LF-240,1%,1/16W,EMPTA CS12402FB03              R1394           

----------------

Q_RES_0402LF-249,1%,1/16W,CHIPA CS12492FB12              R662            
Q_RES_0402LF-249,1%,1/16W,CHIPA CS12492FB12              R663            
Q_RES_0402LF-249,1%,1/16W,CHIPA CS12492FB12              R664            
Q_RES_0402LF-249,1%,1/16W,CHIPA CS12492FB12              R669            
Q_RES_0402LF-249,1%,1/16W,CHIPA CS12492FB12              R679            
Q_RES_0402LF-249,1%,1/16W,CHIPA CS12492FB12              R680            
Q_RES_0402LF-249,1%,1/16W,CHIPA CS12492FB12              R681            
Q_RES_0402LF-249,1%,1/16W,CHIPA CS12492FB12              R686            
Q_RES_0402LF-249,1%,1/16W,CHIPA CS12492FB12              R1241           
Q_RES_0402LF-249,1%,1/16W,CHIPA CS12492FB12              R1243           

----------------

Q_RES_0402LF-26.1K,1%,1/16W,CHA CS32612FB09              R2381           

----------------

Q_RES_0402LF-26.1K,1%,1/16W,EMA CS32612FB09              R2336           

----------------

Q_RES_0402LF-27.4,1%,1/16W,CHIA CS02742FB19              R1140           
Q_RES_0402LF-27.4,1%,1/16W,CHIA CS02742FB19              R1141           

----------------

Q_RES_0402LF-28K,1%,1/16W,EMPTA CS32802FB05              PR105           
Q_RES_0402LF-28K,1%,1/16W,EMPTA CS32802FB05              PR159           
Q_RES_0402LF-28K,1%,1/16W,EMPTA CS32802FB05              PR202           
Q_RES_0402LF-28K,1%,1/16W,EMPTA CS32802FB05              PR258           
Q_RES_0402LF-28K,1%,1/16W,EMPTA CS32802FB05              PR306           
Q_RES_0402LF-28K,1%,1/16W,EMPTA CS32802FB05              PR357           

----------------

Q_RES_0402LF-2K,1%,1/16W,CHIP,A CS22002FB19              R106            
Q_RES_0402LF-2K,1%,1/16W,CHIP,A CS22002FB19              R990            
Q_RES_0402LF-2K,1%,1/16W,CHIP,A CS22002FB19              R991            
Q_RES_0402LF-2K,1%,1/16W,CHIP,A CS22002FB19              R992            
Q_RES_0402LF-2K,1%,1/16W,CHIP,A CS22002FB19              R1302           
Q_RES_0402LF-2K,1%,1/16W,CHIP,A CS22002FB19              R1319           
Q_RES_0402LF-2K,1%,1/16W,CHIP,A CS22002FB19              R1321           
Q_RES_0402LF-2K,1%,1/16W,CHIP,A CS22002FB19              R1326           
Q_RES_0402LF-2K,1%,1/16W,CHIP,A CS22002FB19              R1327           
Q_RES_0402LF-2K,1%,1/16W,CHIP,A CS22002FB19              R1328           
Q_RES_0402LF-2K,1%,1/16W,CHIP,A CS22002FB19              R1329           
Q_RES_0402LF-2K,1%,1/16W,CHIP,A CS22002FB19              R1330           
Q_RES_0402LF-2K,1%,1/16W,CHIP,A CS22002FB19              R1384           
Q_RES_0402LF-2K,1%,1/16W,CHIP,A CS22002FB19              R1385           
Q_RES_0402LF-2K,1%,1/16W,CHIP,A CS22002FB19              R1386           
Q_RES_0402LF-2K,1%,1/16W,CHIP,A CS22002FB19              R1387           
Q_RES_0402LF-2K,1%,1/16W,CHIP,A CS22002FB19              R1388           
Q_RES_0402LF-2K,1%,1/16W,CHIP,A CS22002FB19              R1389           
Q_RES_0402LF-2K,1%,1/16W,CHIP,A CS22002FB19              R1398           
Q_RES_0402LF-2K,1%,1/16W,CHIP,A CS22002FB19              R1402           
Q_RES_0402LF-2K,1%,1/16W,CHIP,A CS22002FB19              R1403           
Q_RES_0402LF-2K,1%,1/16W,CHIP,A CS22002FB19              R1404           
Q_RES_0402LF-2K,1%,1/16W,CHIP,A CS22002FB19              R1405           
Q_RES_0402LF-2K,1%,1/16W,CHIP,A CS22002FB19              R1406           
Q_RES_0402LF-2K,1%,1/16W,CHIP,A CS22002FB19              R1407           
Q_RES_0402LF-2K,1%,1/16W,CHIP,A CS22002FB19              R1408           
Q_RES_0402LF-2K,1%,1/16W,CHIP,A CS22002FB19              R1409           
Q_RES_0402LF-2K,1%,1/16W,CHIP,A CS22002FB19              R1410           
Q_RES_0402LF-2K,1%,1/16W,CHIP,A CS22002FB19              R1411           
Q_RES_0402LF-2K,1%,1/16W,CHIP,A CS22002FB19              R1412           
Q_RES_0402LF-2K,1%,1/16W,CHIP,A CS22002FB19              R1413           
Q_RES_0402LF-2K,1%,1/16W,CHIP,A CS22002FB19              R1414           
Q_RES_0402LF-2K,1%,1/16W,CHIP,A CS22002FB19              R1415           
Q_RES_0402LF-2K,1%,1/16W,CHIP,A CS22002FB19              R1416           
Q_RES_0402LF-2K,1%,1/16W,CHIP,A CS22002FB19              R1417           
Q_RES_0402LF-2K,1%,1/16W,CHIP,A CS22002FB19              R1418           
Q_RES_0402LF-2K,1%,1/16W,CHIP,A CS22002FB19              R1419           
Q_RES_0402LF-2K,1%,1/16W,CHIP,A CS22002FB19              R1420           
Q_RES_0402LF-2K,1%,1/16W,CHIP,A CS22002FB19              R1421           
Q_RES_0402LF-2K,1%,1/16W,CHIP,A CS22002FB19              R1445           
Q_RES_0402LF-2K,1%,1/16W,CHIP,A CS22002FB19              R1451           
Q_RES_0402LF-2K,1%,1/16W,CHIP,A CS22002FB19              R1452           
Q_RES_0402LF-2K,1%,1/16W,CHIP,A CS22002FB19              R1453           
Q_RES_0402LF-2K,1%,1/16W,CHIP,A CS22002FB19              R1454           
Q_RES_0402LF-2K,1%,1/16W,CHIP,A CS22002FB19              R1545           
Q_RES_0402LF-2K,1%,1/16W,CHIP,A CS22002FB19              R1546           
Q_RES_0402LF-2K,1%,1/16W,CHIP,A CS22002FB19              R1581           
Q_RES_0402LF-2K,1%,1/16W,CHIP,A CS22002FB19              R1582           
Q_RES_0402LF-2K,1%,1/16W,CHIP,A CS22002FB19              R1649           
Q_RES_0402LF-2K,1%,1/16W,CHIP,A CS22002FB19              R1731           
Q_RES_0402LF-2K,1%,1/16W,CHIP,A CS22002FB19              R1732           
Q_RES_0402LF-2K,1%,1/16W,CHIP,A CS22002FB19              R2374           
Q_RES_0402LF-2K,1%,1/16W,CHIP,A CS22002FB19              R2385           

----------------

Q_RES_0402LF-2K,1%,1/16W,EMPTYA CS22002FB19              R2332           

----------------

Q_RES_0402LF-3.3,1%,1/16W,CHIPA CS-3302FB00              PR1766          
Q_RES_0402LF-3.3,1%,1/16W,CHIPA CS-3302FB00              PR1767          
Q_RES_0402LF-3.3,1%,1/16W,CHIPA CS-3302FB00              PR1768          
Q_RES_0402LF-3.3,1%,1/16W,CHIPA CS-3302FB00              PR1769          
Q_RES_0402LF-3.3,1%,1/16W,CHIPA CS-3302FB00              PR1770          
Q_RES_0402LF-3.3,1%,1/16W,CHIPA CS-3302FB00              PR1771          
Q_RES_0402LF-3.3,1%,1/16W,CHIPA CS-3302FB00              PR1772          
Q_RES_0402LF-3.3,1%,1/16W,CHIPA CS-3302FB00              PR1773          
Q_RES_0402LF-3.3,1%,1/16W,CHIPA CS-3302FB00              PR1780          
Q_RES_0402LF-3.3,1%,1/16W,CHIPA CS-3302FB00              PR1781          
Q_RES_0402LF-3.3,1%,1/16W,CHIPA CS-3302FB00              PR1786          
Q_RES_0402LF-3.3,1%,1/16W,CHIPA CS-3302FB00              PR1787          
Q_RES_0402LF-3.3,1%,1/16W,CHIPA CS-3302FB00              PR1788          
Q_RES_0402LF-3.3,1%,1/16W,CHIPA CS-3302FB00              PR1789          
Q_RES_0402LF-3.3,1%,1/16W,CHIPA CS-3302FB00              PR1790          
Q_RES_0402LF-3.3,1%,1/16W,CHIPA CS-3302FB00              PR1791          
Q_RES_0402LF-3.3,1%,1/16W,CHIPA CS-3302FB00              PR1792          
Q_RES_0402LF-3.3,1%,1/16W,CHIPA CS-3302FB00              PR1793          
Q_RES_0402LF-3.3,1%,1/16W,CHIPA CS-3302FB00              PR1800          
Q_RES_0402LF-3.3,1%,1/16W,CHIPA CS-3302FB00              PR1801          
Q_RES_0402LF-3.3,1%,1/16W,CHIPA CS-3302FB00              PR1802          
Q_RES_0402LF-3.3,1%,1/16W,CHIPA CS-3302FB00              PR1803          

----------------

Q_RES_0402LF-3.3,1%,1/16W,EMPTA CS-3302FB00              PR1782          
Q_RES_0402LF-3.3,1%,1/16W,EMPTA CS-3302FB00              PR1783          

----------------

Q_RES_0402LF-30.1K    ,1%  ,1/A CS33012FB18              PR203           

----------------

Q_RES_0402LF-301,1%,1/16W,CHIPA CS13012FB14              R296            
Q_RES_0402LF-301,1%,1/16W,CHIPA CS13012FB14              R298            
Q_RES_0402LF-301,1%,1/16W,CHIPA CS13012FB14              R301            
Q_RES_0402LF-301,1%,1/16W,CHIPA CS13012FB14              R303            
Q_RES_0402LF-301,1%,1/16W,CHIPA CS13012FB14              R1242           
Q_RES_0402LF-301,1%,1/16W,CHIPA CS13012FB14              R1244           

----------------

Q_RES_0402LF-31.6K,1%,1/16W,CHA CS33162FB14              PR830           

----------------

Q_RES_0402LF-33,5%,1/16W,CHIP,A CS03302JB29              R100            
Q_RES_0402LF-33,5%,1/16W,CHIP,A CS03302JB29              R104            
Q_RES_0402LF-33,5%,1/16W,CHIP,A CS03302JB29              R156            
Q_RES_0402LF-33,5%,1/16W,CHIP,A CS03302JB29              R158            
Q_RES_0402LF-33,5%,1/16W,CHIP,A CS03302JB29              R184            
Q_RES_0402LF-33,5%,1/16W,CHIP,A CS03302JB29              R186            
Q_RES_0402LF-33,5%,1/16W,CHIP,A CS03302JB29              R203            
Q_RES_0402LF-33,5%,1/16W,CHIP,A CS03302JB29              R204            
Q_RES_0402LF-33,5%,1/16W,CHIP,A CS03302JB29              R205            
Q_RES_0402LF-33,5%,1/16W,CHIP,A CS03302JB29              R206            
Q_RES_0402LF-33,5%,1/16W,CHIP,A CS03302JB29              R315            
Q_RES_0402LF-33,5%,1/16W,CHIP,A CS03302JB29              R338            
Q_RES_0402LF-33,5%,1/16W,CHIP,A CS03302JB29              R339            
Q_RES_0402LF-33,5%,1/16W,CHIP,A CS03302JB29              R342            
Q_RES_0402LF-33,5%,1/16W,CHIP,A CS03302JB29              R343            
Q_RES_0402LF-33,5%,1/16W,CHIP,A CS03302JB29              R346            
Q_RES_0402LF-33,5%,1/16W,CHIP,A CS03302JB29              R347            
Q_RES_0402LF-33,5%,1/16W,CHIP,A CS03302JB29              R474            
Q_RES_0402LF-33,5%,1/16W,CHIP,A CS03302JB29              R577            
Q_RES_0402LF-33,5%,1/16W,CHIP,A CS03302JB29              R578            
Q_RES_0402LF-33,5%,1/16W,CHIP,A CS03302JB29              R579            
Q_RES_0402LF-33,5%,1/16W,CHIP,A CS03302JB29              R580            
Q_RES_0402LF-33,5%,1/16W,CHIP,A CS03302JB29              R581            
Q_RES_0402LF-33,5%,1/16W,CHIP,A CS03302JB29              R582            
Q_RES_0402LF-33,5%,1/16W,CHIP,A CS03302JB29              R585            
Q_RES_0402LF-33,5%,1/16W,CHIP,A CS03302JB29              R586            
Q_RES_0402LF-33,5%,1/16W,CHIP,A CS03302JB29              R697            
Q_RES_0402LF-33,5%,1/16W,CHIP,A CS03302JB29              R699            
Q_RES_0402LF-33,5%,1/16W,CHIP,A CS03302JB29              R723            
Q_RES_0402LF-33,5%,1/16W,CHIP,A CS03302JB29              R724            
Q_RES_0402LF-33,5%,1/16W,CHIP,A CS03302JB29              R745            
Q_RES_0402LF-33,5%,1/16W,CHIP,A CS03302JB29              R803            
Q_RES_0402LF-33,5%,1/16W,CHIP,A CS03302JB29              R804            
Q_RES_0402LF-33,5%,1/16W,CHIP,A CS03302JB29              R805            
Q_RES_0402LF-33,5%,1/16W,CHIP,A CS03302JB29              R806            
Q_RES_0402LF-33,5%,1/16W,CHIP,A CS03302JB29              R877            
Q_RES_0402LF-33,5%,1/16W,CHIP,A CS03302JB29              R878            
Q_RES_0402LF-33,5%,1/16W,CHIP,A CS03302JB29              R879            
Q_RES_0402LF-33,5%,1/16W,CHIP,A CS03302JB29              R880            
Q_RES_0402LF-33,5%,1/16W,CHIP,A CS03302JB29              R881            
Q_RES_0402LF-33,5%,1/16W,CHIP,A CS03302JB29              R882            
Q_RES_0402LF-33,5%,1/16W,CHIP,A CS03302JB29              R883            
Q_RES_0402LF-33,5%,1/16W,CHIP,A CS03302JB29              R884            
Q_RES_0402LF-33,5%,1/16W,CHIP,A CS03302JB29              R885            
Q_RES_0402LF-33,5%,1/16W,CHIP,A CS03302JB29              R886            
Q_RES_0402LF-33,5%,1/16W,CHIP,A CS03302JB29              R887            
Q_RES_0402LF-33,5%,1/16W,CHIP,A CS03302JB29              R888            
Q_RES_0402LF-33,5%,1/16W,CHIP,A CS03302JB29              R889            
Q_RES_0402LF-33,5%,1/16W,CHIP,A CS03302JB29              R890            
Q_RES_0402LF-33,5%,1/16W,CHIP,A CS03302JB29              R891            
Q_RES_0402LF-33,5%,1/16W,CHIP,A CS03302JB29              R892            
Q_RES_0402LF-33,5%,1/16W,CHIP,A CS03302JB29              R893            
Q_RES_0402LF-33,5%,1/16W,CHIP,A CS03302JB29              R894            
Q_RES_0402LF-33,5%,1/16W,CHIP,A CS03302JB29              R895            
Q_RES_0402LF-33,5%,1/16W,CHIP,A CS03302JB29              R896            
Q_RES_0402LF-33,5%,1/16W,CHIP,A CS03302JB29              R897            
Q_RES_0402LF-33,5%,1/16W,CHIP,A CS03302JB29              R898            
Q_RES_0402LF-33,5%,1/16W,CHIP,A CS03302JB29              R899            
Q_RES_0402LF-33,5%,1/16W,CHIP,A CS03302JB29              R900            
Q_RES_0402LF-33,5%,1/16W,CHIP,A CS03302JB29              R901            
Q_RES_0402LF-33,5%,1/16W,CHIP,A CS03302JB29              R902            
Q_RES_0402LF-33,5%,1/16W,CHIP,A CS03302JB29              R903            
Q_RES_0402LF-33,5%,1/16W,CHIP,A CS03302JB29              R904            
Q_RES_0402LF-33,5%,1/16W,CHIP,A CS03302JB29              R905            
Q_RES_0402LF-33,5%,1/16W,CHIP,A CS03302JB29              R906            
Q_RES_0402LF-33,5%,1/16W,CHIP,A CS03302JB29              R907            
Q_RES_0402LF-33,5%,1/16W,CHIP,A CS03302JB29              R908            
Q_RES_0402LF-33,5%,1/16W,CHIP,A CS03302JB29              R955            
Q_RES_0402LF-33,5%,1/16W,CHIP,A CS03302JB29              R981            
Q_RES_0402LF-33,5%,1/16W,CHIP,A CS03302JB29              R982            
Q_RES_0402LF-33,5%,1/16W,CHIP,A CS03302JB29              R983            
Q_RES_0402LF-33,5%,1/16W,CHIP,A CS03302JB29              R984            
Q_RES_0402LF-33,5%,1/16W,CHIP,A CS03302JB29              R985            
Q_RES_0402LF-33,5%,1/16W,CHIP,A CS03302JB29              R986            
Q_RES_0402LF-33,5%,1/16W,CHIP,A CS03302JB29              R987            
Q_RES_0402LF-33,5%,1/16W,CHIP,A CS03302JB29              R988            
Q_RES_0402LF-33,5%,1/16W,CHIP,A CS03302JB29              R1130           
Q_RES_0402LF-33,5%,1/16W,CHIP,A CS03302JB29              R1131           
Q_RES_0402LF-33,5%,1/16W,CHIP,A CS03302JB29              R1205           
Q_RES_0402LF-33,5%,1/16W,CHIP,A CS03302JB29              R1206           
Q_RES_0402LF-33,5%,1/16W,CHIP,A CS03302JB29              R1207           
Q_RES_0402LF-33,5%,1/16W,CHIP,A CS03302JB29              R1263           
Q_RES_0402LF-33,5%,1/16W,CHIP,A CS03302JB29              R1268           
Q_RES_0402LF-33,5%,1/16W,CHIP,A CS03302JB29              R1600           
Q_RES_0402LF-33,5%,1/16W,CHIP,A CS03302JB29              R1656           
Q_RES_0402LF-33,5%,1/16W,CHIP,A CS03302JB29              R1657           
Q_RES_0402LF-33,5%,1/16W,CHIP,A CS03302JB29              R1661           
Q_RES_0402LF-33,5%,1/16W,CHIP,A CS03302JB29              R1662           
Q_RES_0402LF-33,5%,1/16W,CHIP,A CS03302JB29              R1761           
Q_RES_0402LF-33,5%,1/16W,CHIP,A CS03302JB29              R1762           
Q_RES_0402LF-33,5%,1/16W,CHIP,A CS03302JB29              R1827           
Q_RES_0402LF-33,5%,1/16W,CHIP,A CS03302JB29              R1921           
Q_RES_0402LF-33,5%,1/16W,CHIP,A CS03302JB29              R1995           
Q_RES_0402LF-33,5%,1/16W,CHIP,A CS03302JB29              R1996           
Q_RES_0402LF-33,5%,1/16W,CHIP,A CS03302JB29              R2101           
Q_RES_0402LF-33,5%,1/16W,CHIP,A CS03302JB29              R2102           
Q_RES_0402LF-33,5%,1/16W,CHIP,A CS03302JB29              R2103           
Q_RES_0402LF-33,5%,1/16W,CHIP,A CS03302JB29              R2104           
Q_RES_0402LF-33,5%,1/16W,CHIP,A CS03302JB29              R2186           

----------------

Q_RES_0402LF-33.2,1%,1/16W,CHIA CS03322FB34              R3              
Q_RES_0402LF-33.2,1%,1/16W,CHIA CS03322FB34              R7              
Q_RES_0402LF-33.2,1%,1/16W,CHIA CS03322FB34              R10             
Q_RES_0402LF-33.2,1%,1/16W,CHIA CS03322FB34              R11             
Q_RES_0402LF-33.2,1%,1/16W,CHIA CS03322FB34              R63             
Q_RES_0402LF-33.2,1%,1/16W,CHIA CS03322FB34              R67             
Q_RES_0402LF-33.2,1%,1/16W,CHIA CS03322FB34              R68             
Q_RES_0402LF-33.2,1%,1/16W,CHIA CS03322FB34              R108            
Q_RES_0402LF-33.2,1%,1/16W,CHIA CS03322FB34              R109            
Q_RES_0402LF-33.2,1%,1/16W,CHIA CS03322FB34              R110            
Q_RES_0402LF-33.2,1%,1/16W,CHIA CS03322FB34              R113            
Q_RES_0402LF-33.2,1%,1/16W,CHIA CS03322FB34              R269            
Q_RES_0402LF-33.2,1%,1/16W,CHIA CS03322FB34              R302            
Q_RES_0402LF-33.2,1%,1/16W,CHIA CS03322FB34              R304            
Q_RES_0402LF-33.2,1%,1/16W,CHIA CS03322FB34              R322            
Q_RES_0402LF-33.2,1%,1/16W,CHIA CS03322FB34              R419            
Q_RES_0402LF-33.2,1%,1/16W,CHIA CS03322FB34              R424            
Q_RES_0402LF-33.2,1%,1/16W,CHIA CS03322FB34              R425            
Q_RES_0402LF-33.2,1%,1/16W,CHIA CS03322FB34              R435            
Q_RES_0402LF-33.2,1%,1/16W,CHIA CS03322FB34              R459            
Q_RES_0402LF-33.2,1%,1/16W,CHIA CS03322FB34              R460            
Q_RES_0402LF-33.2,1%,1/16W,CHIA CS03322FB34              R475            
Q_RES_0402LF-33.2,1%,1/16W,CHIA CS03322FB34              R499            
Q_RES_0402LF-33.2,1%,1/16W,CHIA CS03322FB34              R500            
Q_RES_0402LF-33.2,1%,1/16W,CHIA CS03322FB34              R501            
Q_RES_0402LF-33.2,1%,1/16W,CHIA CS03322FB34              R588            
Q_RES_0402LF-33.2,1%,1/16W,CHIA CS03322FB34              R589            
Q_RES_0402LF-33.2,1%,1/16W,CHIA CS03322FB34              R647            
Q_RES_0402LF-33.2,1%,1/16W,CHIA CS03322FB34              R670            
Q_RES_0402LF-33.2,1%,1/16W,CHIA CS03322FB34              R671            
Q_RES_0402LF-33.2,1%,1/16W,CHIA CS03322FB34              R672            
Q_RES_0402LF-33.2,1%,1/16W,CHIA CS03322FB34              R673            
Q_RES_0402LF-33.2,1%,1/16W,CHIA CS03322FB34              R687            
Q_RES_0402LF-33.2,1%,1/16W,CHIA CS03322FB34              R688            
Q_RES_0402LF-33.2,1%,1/16W,CHIA CS03322FB34              R689            
Q_RES_0402LF-33.2,1%,1/16W,CHIA CS03322FB34              R690            
Q_RES_0402LF-33.2,1%,1/16W,CHIA CS03322FB34              R709            
Q_RES_0402LF-33.2,1%,1/16W,CHIA CS03322FB34              R725            
Q_RES_0402LF-33.2,1%,1/16W,CHIA CS03322FB34              R726            
Q_RES_0402LF-33.2,1%,1/16W,CHIA CS03322FB34              R909            
Q_RES_0402LF-33.2,1%,1/16W,CHIA CS03322FB34              R915            
Q_RES_0402LF-33.2,1%,1/16W,CHIA CS03322FB34              R916            
Q_RES_0402LF-33.2,1%,1/16W,CHIA CS03322FB34              R917            
Q_RES_0402LF-33.2,1%,1/16W,CHIA CS03322FB34              R918            
Q_RES_0402LF-33.2,1%,1/16W,CHIA CS03322FB34              R923            
Q_RES_0402LF-33.2,1%,1/16W,CHIA CS03322FB34              R960            
Q_RES_0402LF-33.2,1%,1/16W,CHIA CS03322FB34              R961            
Q_RES_0402LF-33.2,1%,1/16W,CHIA CS03322FB34              R962            
Q_RES_0402LF-33.2,1%,1/16W,CHIA CS03322FB34              R973            
Q_RES_0402LF-33.2,1%,1/16W,CHIA CS03322FB34              R974            
Q_RES_0402LF-33.2,1%,1/16W,CHIA CS03322FB34              R975            
Q_RES_0402LF-33.2,1%,1/16W,CHIA CS03322FB34              R976            
Q_RES_0402LF-33.2,1%,1/16W,CHIA CS03322FB34              R993            
Q_RES_0402LF-33.2,1%,1/16W,CHIA CS03322FB34              R994            
Q_RES_0402LF-33.2,1%,1/16W,CHIA CS03322FB34              R995            
Q_RES_0402LF-33.2,1%,1/16W,CHIA CS03322FB34              R996            
Q_RES_0402LF-33.2,1%,1/16W,CHIA CS03322FB34              R1057           
Q_RES_0402LF-33.2,1%,1/16W,CHIA CS03322FB34              R1100           
Q_RES_0402LF-33.2,1%,1/16W,CHIA CS03322FB34              R1218           
Q_RES_0402LF-33.2,1%,1/16W,CHIA CS03322FB34              R1219           
Q_RES_0402LF-33.2,1%,1/16W,CHIA CS03322FB34              R1300           
Q_RES_0402LF-33.2,1%,1/16W,CHIA CS03322FB34              R1306           
Q_RES_0402LF-33.2,1%,1/16W,CHIA CS03322FB34              R1307           
Q_RES_0402LF-33.2,1%,1/16W,CHIA CS03322FB34              R1309           
Q_RES_0402LF-33.2,1%,1/16W,CHIA CS03322FB34              R1310           
Q_RES_0402LF-33.2,1%,1/16W,CHIA CS03322FB34              R1313           
Q_RES_0402LF-33.2,1%,1/16W,CHIA CS03322FB34              R1318           
Q_RES_0402LF-33.2,1%,1/16W,CHIA CS03322FB34              R1378           
Q_RES_0402LF-33.2,1%,1/16W,CHIA CS03322FB34              R1379           
Q_RES_0402LF-33.2,1%,1/16W,CHIA CS03322FB34              R1395           
Q_RES_0402LF-33.2,1%,1/16W,CHIA CS03322FB34              R1423           
Q_RES_0402LF-33.2,1%,1/16W,CHIA CS03322FB34              R1442           
Q_RES_0402LF-33.2,1%,1/16W,CHIA CS03322FB34              R1443           
Q_RES_0402LF-33.2,1%,1/16W,CHIA CS03322FB34              R1444           
Q_RES_0402LF-33.2,1%,1/16W,CHIA CS03322FB34              R1446           
Q_RES_0402LF-33.2,1%,1/16W,CHIA CS03322FB34              R1447           
Q_RES_0402LF-33.2,1%,1/16W,CHIA CS03322FB34              R1448           
Q_RES_0402LF-33.2,1%,1/16W,CHIA CS03322FB34              R1469           
Q_RES_0402LF-33.2,1%,1/16W,CHIA CS03322FB34              R1470           
Q_RES_0402LF-33.2,1%,1/16W,CHIA CS03322FB34              R1472           
Q_RES_0402LF-33.2,1%,1/16W,CHIA CS03322FB34              R1479           
Q_RES_0402LF-33.2,1%,1/16W,CHIA CS03322FB34              R1481           
Q_RES_0402LF-33.2,1%,1/16W,CHIA CS03322FB34              R1482           
Q_RES_0402LF-33.2,1%,1/16W,CHIA CS03322FB34              R1504           
Q_RES_0402LF-33.2,1%,1/16W,CHIA CS03322FB34              R1505           
Q_RES_0402LF-33.2,1%,1/16W,CHIA CS03322FB34              R1512           
Q_RES_0402LF-33.2,1%,1/16W,CHIA CS03322FB34              R1513           
Q_RES_0402LF-33.2,1%,1/16W,CHIA CS03322FB34              R1514           
Q_RES_0402LF-33.2,1%,1/16W,CHIA CS03322FB34              R1515           
Q_RES_0402LF-33.2,1%,1/16W,CHIA CS03322FB34              R1516           
Q_RES_0402LF-33.2,1%,1/16W,CHIA CS03322FB34              R1518           
Q_RES_0402LF-33.2,1%,1/16W,CHIA CS03322FB34              R1519           
Q_RES_0402LF-33.2,1%,1/16W,CHIA CS03322FB34              R1520           
Q_RES_0402LF-33.2,1%,1/16W,CHIA CS03322FB34              R1521           
Q_RES_0402LF-33.2,1%,1/16W,CHIA CS03322FB34              R1526           
Q_RES_0402LF-33.2,1%,1/16W,CHIA CS03322FB34              R1537           
Q_RES_0402LF-33.2,1%,1/16W,CHIA CS03322FB34              R1538           
Q_RES_0402LF-33.2,1%,1/16W,CHIA CS03322FB34              R1594           
Q_RES_0402LF-33.2,1%,1/16W,CHIA CS03322FB34              R1595           
Q_RES_0402LF-33.2,1%,1/16W,CHIA CS03322FB34              R1693           
Q_RES_0402LF-33.2,1%,1/16W,CHIA CS03322FB34              R1719           
Q_RES_0402LF-33.2,1%,1/16W,CHIA CS03322FB34              R1751           
Q_RES_0402LF-33.2,1%,1/16W,CHIA CS03322FB34              R1752           
Q_RES_0402LF-33.2,1%,1/16W,CHIA CS03322FB34              R1753           
Q_RES_0402LF-33.2,1%,1/16W,CHIA CS03322FB34              R1754           
Q_RES_0402LF-33.2,1%,1/16W,CHIA CS03322FB34              R1755           
Q_RES_0402LF-33.2,1%,1/16W,CHIA CS03322FB34              R1756           
Q_RES_0402LF-33.2,1%,1/16W,CHIA CS03322FB34              R1757           
Q_RES_0402LF-33.2,1%,1/16W,CHIA CS03322FB34              R1758           
Q_RES_0402LF-33.2,1%,1/16W,CHIA CS03322FB34              R1811           
Q_RES_0402LF-33.2,1%,1/16W,CHIA CS03322FB34              R1812           
Q_RES_0402LF-33.2,1%,1/16W,CHIA CS03322FB34              R1842           
Q_RES_0402LF-33.2,1%,1/16W,CHIA CS03322FB34              R1843           
Q_RES_0402LF-33.2,1%,1/16W,CHIA CS03322FB34              R1844           
Q_RES_0402LF-33.2,1%,1/16W,CHIA CS03322FB34              R1919           
Q_RES_0402LF-33.2,1%,1/16W,CHIA CS03322FB34              R1932           
Q_RES_0402LF-33.2,1%,1/16W,CHIA CS03322FB34              R1933           
Q_RES_0402LF-33.2,1%,1/16W,CHIA CS03322FB34              R1934           
Q_RES_0402LF-33.2,1%,1/16W,CHIA CS03322FB34              R1935           
Q_RES_0402LF-33.2,1%,1/16W,CHIA CS03322FB34              R1940           
Q_RES_0402LF-33.2,1%,1/16W,CHIA CS03322FB34              R1941           
Q_RES_0402LF-33.2,1%,1/16W,CHIA CS03322FB34              R1966           
Q_RES_0402LF-33.2,1%,1/16W,CHIA CS03322FB34              R1971           
Q_RES_0402LF-33.2,1%,1/16W,CHIA CS03322FB34              R1976           
Q_RES_0402LF-33.2,1%,1/16W,CHIA CS03322FB34              R1981           
Q_RES_0402LF-33.2,1%,1/16W,CHIA CS03322FB34              R1986           
Q_RES_0402LF-33.2,1%,1/16W,CHIA CS03322FB34              R1991           
Q_RES_0402LF-33.2,1%,1/16W,CHIA CS03322FB34              R2050           
Q_RES_0402LF-33.2,1%,1/16W,CHIA CS03322FB34              R2077           
Q_RES_0402LF-33.2,1%,1/16W,CHIA CS03322FB34              R2078           
Q_RES_0402LF-33.2,1%,1/16W,CHIA CS03322FB34              R2129           
Q_RES_0402LF-33.2,1%,1/16W,CHIA CS03322FB34              R2171           

----------------

Q_RES_0402LF-332,1%,1/16W,CHIPA CS13322FB10              R366            

----------------

Q_RES_0402LF-33K    ,1%  ,1/16A CS33302FB14              R1799           

----------------

Q_RES_0402LF-35.7K,1%,1/16W,CHA CS33572FB13              R29             
Q_RES_0402LF-35.7K,1%,1/16W,CHA CS33572FB13              R37             
Q_RES_0402LF-35.7K,1%,1/16W,CHA CS33572FB13              R45             
Q_RES_0402LF-35.7K,1%,1/16W,CHA CS33572FB13              R76             

----------------

Q_RES_0402LF-36K,1%,1/16W,CHIPA CS33602FB15              PR1340          

----------------

Q_RES_0402LF-36K,1%,1/16W,EMPTA CS33602FB15              PR1337          

----------------

Q_RES_0402LF-4.32K,1%,1/16W,CHA CS24322FB14              R9              
Q_RES_0402LF-4.32K,1%,1/16W,CHA CS24322FB14              R316            

----------------

Q_RES_0402LF-4.64K,0.5%,1/16W,A CS24642DB00              PR358           

----------------

Q_RES_0402LF-4.7,1%,1/16W,CHIPA CS-4702FB19              PR1774          
Q_RES_0402LF-4.7,1%,1/16W,CHIPA CS-4702FB19              PR1775          
Q_RES_0402LF-4.7,1%,1/16W,CHIPA CS-4702FB19              PR1778          
Q_RES_0402LF-4.7,1%,1/16W,CHIPA CS-4702FB19              PR1784          
Q_RES_0402LF-4.7,1%,1/16W,CHIPA CS-4702FB19              PR1794          
Q_RES_0402LF-4.7,1%,1/16W,CHIPA CS-4702FB19              PR1795          
Q_RES_0402LF-4.7,1%,1/16W,CHIPA CS-4702FB19              PR1798          
Q_RES_0402LF-4.7,1%,1/16W,CHIPA CS-4702FB19              PR1804          

----------------

Q_RES_0402LF-4.75K,1%,1/16W,CHA CS24752FB12              R494            
Q_RES_0402LF-4.75K,1%,1/16W,CHA CS24752FB12              R696            
Q_RES_0402LF-4.75K,1%,1/16W,CHA CS24752FB12              R734            
Q_RES_0402LF-4.75K,1%,1/16W,CHA CS24752FB12              R953            
Q_RES_0402LF-4.75K,1%,1/16W,CHA CS24752FB12              R1196           
Q_RES_0402LF-4.75K,1%,1/16W,CHA CS24752FB12              R1269           
Q_RES_0402LF-4.75K,1%,1/16W,CHA CS24752FB12              R1471           
Q_RES_0402LF-4.75K,1%,1/16W,CHA CS24752FB12              R1500           
Q_RES_0402LF-4.75K,1%,1/16W,CHA CS24752FB12              R1502           

----------------

Q_RES_0402LF-4.75K,1%,1/16W,EMA CS24752FB12              R146            
Q_RES_0402LF-4.75K,1%,1/16W,EMA CS24752FB12              R562            
Q_RES_0402LF-4.75K,1%,1/16W,EMA CS24752FB12              R912            
Q_RES_0402LF-4.75K,1%,1/16W,EMA CS24752FB12              R1194           

----------------

Q_RES_0402LF-4.7K,1%,1/16W,CHIA CS24702FB10              R410            
Q_RES_0402LF-4.7K,1%,1/16W,CHIA CS24702FB10              R415            
Q_RES_0402LF-4.7K,1%,1/16W,CHIA CS24702FB10              R478            
Q_RES_0402LF-4.7K,1%,1/16W,CHIA CS24702FB10              R568            
Q_RES_0402LF-4.7K,1%,1/16W,CHIA CS24702FB10              R570            
Q_RES_0402LF-4.7K,1%,1/16W,CHIA CS24702FB10              R574            
Q_RES_0402LF-4.7K,1%,1/16W,CHIA CS24702FB10              R930            
Q_RES_0402LF-4.7K,1%,1/16W,CHIA CS24702FB10              R1467           
Q_RES_0402LF-4.7K,1%,1/16W,CHIA CS24702FB10              R1549           
Q_RES_0402LF-4.7K,1%,1/16W,CHIA CS24702FB10              R1550           
Q_RES_0402LF-4.7K,1%,1/16W,CHIA CS24702FB10              R1551           
Q_RES_0402LF-4.7K,1%,1/16W,CHIA CS24702FB10              R1785           
Q_RES_0402LF-4.7K,1%,1/16W,CHIA CS24702FB10              R2157           

----------------

Q_RES_0402LF-4.7K,1%,1/16W,EMPA CS24702FB10              R409            
Q_RES_0402LF-4.7K,1%,1/16W,EMPA CS24702FB10              R414            
Q_RES_0402LF-4.7K,1%,1/16W,EMPA CS24702FB10              R484            
Q_RES_0402LF-4.7K,1%,1/16W,EMPA CS24702FB10              R491            
Q_RES_0402LF-4.7K,1%,1/16W,EMPA CS24702FB10              R567            
Q_RES_0402LF-4.7K,1%,1/16W,EMPA CS24702FB10              R569            
Q_RES_0402LF-4.7K,1%,1/16W,EMPA CS24702FB10              R573            
Q_RES_0402LF-4.7K,1%,1/16W,EMPA CS24702FB10              R952            
Q_RES_0402LF-4.7K,1%,1/16W,EMPA CS24702FB10              R1593           
Q_RES_0402LF-4.7K,1%,1/16W,EMPA CS24702FB10              R1608           
Q_RES_0402LF-4.7K,1%,1/16W,EMPA CS24702FB10              R1784           
Q_RES_0402LF-4.7K,1%,1/16W,EMPA CS24702FB10              R1794           

----------------

Q_RES_0402LF-4.7K,5%,1/16W,CHIA CS24702JB38              R394            
Q_RES_0402LF-4.7K,5%,1/16W,CHIA CS24702JB38              R398            
Q_RES_0402LF-4.7K,5%,1/16W,CHIA CS24702JB38              R402            
Q_RES_0402LF-4.7K,5%,1/16W,CHIA CS24702JB38              R421            
Q_RES_0402LF-4.7K,5%,1/16W,CHIA CS24702JB38              R1000           
Q_RES_0402LF-4.7K,5%,1/16W,CHIA CS24702JB38              R1001           
Q_RES_0402LF-4.7K,5%,1/16W,CHIA CS24702JB38              R1002           
Q_RES_0402LF-4.7K,5%,1/16W,CHIA CS24702JB38              R1003           
Q_RES_0402LF-4.7K,5%,1/16W,CHIA CS24702JB38              R1006           
Q_RES_0402LF-4.7K,5%,1/16W,CHIA CS24702JB38              R1007           
Q_RES_0402LF-4.7K,5%,1/16W,CHIA CS24702JB38              R1331           
Q_RES_0402LF-4.7K,5%,1/16W,CHIA CS24702JB38              R1332           
Q_RES_0402LF-4.7K,5%,1/16W,CHIA CS24702JB38              R1613           
Q_RES_0402LF-4.7K,5%,1/16W,CHIA CS24702JB38              R1615           
Q_RES_0402LF-4.7K,5%,1/16W,CHIA CS24702JB38              R1617           
Q_RES_0402LF-4.7K,5%,1/16W,CHIA CS24702JB38              R1646           
Q_RES_0402LF-4.7K,5%,1/16W,CHIA CS24702JB38              R1700           
Q_RES_0402LF-4.7K,5%,1/16W,CHIA CS24702JB38              R1702           
Q_RES_0402LF-4.7K,5%,1/16W,CHIA CS24702JB38              R1703           
Q_RES_0402LF-4.7K,5%,1/16W,CHIA CS24702JB38              R1967           
Q_RES_0402LF-4.7K,5%,1/16W,CHIA CS24702JB38              R1968           
Q_RES_0402LF-4.7K,5%,1/16W,CHIA CS24702JB38              R1977           
Q_RES_0402LF-4.7K,5%,1/16W,CHIA CS24702JB38              R1978           
Q_RES_0402LF-4.7K,5%,1/16W,CHIA CS24702JB38              R1987           
Q_RES_0402LF-4.7K,5%,1/16W,CHIA CS24702JB38              R1988           
Q_RES_0402LF-4.7K,5%,1/16W,CHIA CS24702JB38              R2000           
Q_RES_0402LF-4.7K,5%,1/16W,CHIA CS24702JB38              R2121           
Q_RES_0402LF-4.7K,5%,1/16W,CHIA CS24702JB38              R2122           
Q_RES_0402LF-4.7K,5%,1/16W,CHIA CS24702JB38              R2123           
Q_RES_0402LF-4.7K,5%,1/16W,CHIA CS24702JB38              R2124           
Q_RES_0402LF-4.7K,5%,1/16W,CHIA CS24702JB38              R2125           
Q_RES_0402LF-4.7K,5%,1/16W,CHIA CS24702JB38              R2126           
Q_RES_0402LF-4.7K,5%,1/16W,CHIA CS24702JB38              R2127           
Q_RES_0402LF-4.7K,5%,1/16W,CHIA CS24702JB38              R2128           

----------------

Q_RES_0402LF-4.7K,5%,1/16W,EMPA CS24702JB38              R640            
Q_RES_0402LF-4.7K,5%,1/16W,EMPA CS24702JB38              R1528           
Q_RES_0402LF-4.7K,5%,1/16W,EMPA CS24702JB38              R1529           
Q_RES_0402LF-4.7K,5%,1/16W,EMPA CS24702JB38              R1530           
Q_RES_0402LF-4.7K,5%,1/16W,EMPA CS24702JB38              R1531           
Q_RES_0402LF-4.7K,5%,1/16W,EMPA CS24702JB38              R1532           
Q_RES_0402LF-4.7K,5%,1/16W,EMPA CS24702JB38              R1533           
Q_RES_0402LF-4.7K,5%,1/16W,EMPA CS24702JB38              R1534           
Q_RES_0402LF-4.7K,5%,1/16W,EMPA CS24702JB38              R1535           
Q_RES_0402LF-4.7K,5%,1/16W,EMPA CS24702JB38              R1536           
Q_RES_0402LF-4.7K,5%,1/16W,EMPA CS24702JB38              R1645           
Q_RES_0402LF-4.7K,5%,1/16W,EMPA CS24702JB38              R1706           
Q_RES_0402LF-4.7K,5%,1/16W,EMPA CS24702JB38              R2079           
Q_RES_0402LF-4.7K,5%,1/16W,EMPA CS24702JB38              R2080           
Q_RES_0402LF-4.7K,5%,1/16W,EMPA CS24702JB38              R2081           
Q_RES_0402LF-4.7K,5%,1/16W,EMPA CS24702JB38              R2082           
Q_RES_0402LF-4.7K,5%,1/16W,EMPA CS24702JB38              R2083           
Q_RES_0402LF-4.7K,5%,1/16W,EMPA CS24702JB38              R2175           
Q_RES_0402LF-4.7K,5%,1/16W,EMPA CS24702JB38              R2176           
Q_RES_0402LF-4.7K,5%,1/16W,EMPA CS24702JB38              R2177           
Q_RES_0402LF-4.7K,5%,1/16W,EMPA CS24702JB38              R2178           
Q_RES_0402LF-4.7K,5%,1/16W,EMPA CS24702JB38              R2179           

----------------

Q_RES_0402LF-412,1%,1/16W,CHIPA CS14122FB15              R977            
Q_RES_0402LF-412,1%,1/16W,CHIPA CS14122FB15              R978            
Q_RES_0402LF-412,1%,1/16W,CHIPA CS14122FB15              R979            
Q_RES_0402LF-412,1%,1/16W,CHIPA CS14122FB15              R980            

----------------

Q_RES_0402LF-49.9     ,1%  ,1/A CS04992FB31              PR529           
Q_RES_0402LF-49.9     ,1%  ,1/A CS04992FB31              PR576           
Q_RES_0402LF-49.9     ,1%  ,1/A CS04992FB31              PR1380          
Q_RES_0402LF-49.9     ,1%  ,1/A CS04992FB31              PR1390          
Q_RES_0402LF-49.9     ,1%  ,1/A CS04992FB31              PR1400          
Q_RES_0402LF-49.9     ,1%  ,1/A CS04992FB31              PR1410          
Q_RES_0402LF-49.9     ,1%  ,1/A CS04992FB31              PR1718          
Q_RES_0402LF-49.9     ,1%  ,1/A CS04992FB31              R195            
Q_RES_0402LF-49.9     ,1%  ,1/A CS04992FB31              R196            
Q_RES_0402LF-49.9     ,1%  ,1/A CS04992FB31              R548            
Q_RES_0402LF-49.9     ,1%  ,1/A CS04992FB31              R556            
Q_RES_0402LF-49.9     ,1%  ,1/A CS04992FB31              R558            
Q_RES_0402LF-49.9     ,1%  ,1/A CS04992FB31              R560            
Q_RES_0402LF-49.9     ,1%  ,1/A CS04992FB31              R575            
Q_RES_0402LF-49.9     ,1%  ,1/A CS04992FB31              R576            
Q_RES_0402LF-49.9     ,1%  ,1/A CS04992FB31              R698            
Q_RES_0402LF-49.9     ,1%  ,1/A CS04992FB31              R780            
Q_RES_0402LF-49.9     ,1%  ,1/A CS04992FB31              R1201           
Q_RES_0402LF-49.9     ,1%  ,1/A CS04992FB31              R1215           
Q_RES_0402LF-49.9     ,1%  ,1/A CS04992FB31              R1455           
Q_RES_0402LF-49.9     ,1%  ,1/A CS04992FB31              R1456           
Q_RES_0402LF-49.9     ,1%  ,1/A CS04992FB31              R1710           
Q_RES_0402LF-49.9     ,1%  ,1/A CS04992FB31              R1717           

----------------

Q_RES_0402LF-49.9     ,1%  ,1/B CS04992FB31              PR530           
Q_RES_0402LF-49.9     ,1%  ,1/B CS04992FB31              PR577           
Q_RES_0402LF-49.9     ,1%  ,1/B CS04992FB31              R1266           
Q_RES_0402LF-49.9     ,1%  ,1/B CS04992FB31              R2322           
Q_RES_0402LF-49.9     ,1%  ,1/B CS04992FB31              R2345           

----------------

Q_RES_0402LF-499,1%,1/16W,CHIPA CS14992FB24              R18             
Q_RES_0402LF-499,1%,1/16W,CHIPA CS14992FB24              R19             
Q_RES_0402LF-499,1%,1/16W,CHIPA CS14992FB24              R49             
Q_RES_0402LF-499,1%,1/16W,CHIPA CS14992FB24              R50             
Q_RES_0402LF-499,1%,1/16W,CHIPA CS14992FB24              R760            
Q_RES_0402LF-499,1%,1/16W,CHIPA CS14992FB24              R761            

----------------

Q_RES_0402LF-5.1,5%,1/16W,CHIPA CS-5102JB03              PR1329          

----------------

Q_RES_0402LF-5.11K,1%,1/16W,CHA CS25112FB15              R1222           

----------------

Q_RES_0402LF-5.23K,1%,1/16W,CHA CS25232FB18              PR318           

----------------

Q_RES_0402LF-510K,5%,1/16W,CHIA CS45102JB16              PR1945          

----------------

Q_RES_0402LF-54.9K,1%,1/16W,CHA CS35492FB14              R30             
Q_RES_0402LF-54.9K,1%,1/16W,CHA CS35492FB14              R38             
Q_RES_0402LF-54.9K,1%,1/16W,CHA CS35492FB14              R46             
Q_RES_0402LF-54.9K,1%,1/16W,CHA CS35492FB14              R75             

----------------

Q_RES_0402LF-562,1%,1/16W,CHIPA CS15622FB01              R1144           

----------------

Q_RES_0402LF-576,1%,1/16W,CHIPA CS15762FB26              R2038           
Q_RES_0402LF-576,1%,1/16W,CHIPA CS15762FB26              R2039           
Q_RES_0402LF-576,1%,1/16W,CHIPA CS15762FB26              R2044           
Q_RES_0402LF-576,1%,1/16W,CHIPA CS15762FB26              R2045           
Q_RES_0402LF-576,1%,1/16W,CHIPA CS15762FB26              R2137           

----------------

Q_RES_0402LF-6.19K,1%,1/16W,CHA CS26192FB14              R1689           

----------------

Q_RES_0402LF-6.81K,1%,1/16W,CHA CS26812FB13              PR1327          

----------------

Q_RES_0402LF-60.4,1%,1/16W,CHIA CS06042FB03              R477            

----------------

Q_RES_0402LF-60.4K,1%,1/16W,CHA CS36042FB10              PR1301          
Q_RES_0402LF-60.4K,1%,1/16W,CHA CS36042FB10              PR2220          

----------------

Q_RES_0402LF-7.32K,1%,1/16W,CHA CS27322FB12              PR1328          

----------------

Q_RES_0402LF-7.5K,1%,1/16W,CHIA CS27502FB11              PR832           

----------------

Q_RES_0402LF-75,1%,1/16W,CHIP,A CS07502FB17              R742            
Q_RES_0402LF-75,1%,1/16W,CHIP,A CS07502FB17              R744            
Q_RES_0402LF-75,1%,1/16W,CHIP,A CS07502FB17              R748            
Q_RES_0402LF-75,1%,1/16W,CHIP,A CS07502FB17              R749            
Q_RES_0402LF-75,1%,1/16W,CHIP,A CS07502FB17              R774            

----------------

Q_RES_0402LF-75,1%,1/16W,EMPTYA CS07502FB17              R1025           

----------------

Q_RES_0402LF-750,1%,1/16W,CHIPA CS17502FB19              R1195           

----------------

Q_RES_0402LF-75K,1%,1/16W,CHIPA CS37502FB12              PR1948          

----------------

Q_RES_0402LF-8.25K,1%,1/16W,CHA CS28252FB03              PR501           
Q_RES_0402LF-8.25K,1%,1/16W,CHA CS28252FB03              PR502           

----------------

Q_RES_0402LF-8.87K,1%,1/16W,EMA CS28872FB01              PR132           
Q_RES_0402LF-8.87K,1%,1/16W,EMA CS28872FB01              PR133           
Q_RES_0402LF-8.87K,1%,1/16W,EMA CS28872FB01              PR138           
Q_RES_0402LF-8.87K,1%,1/16W,EMA CS28872FB01              PR139           
Q_RES_0402LF-8.87K,1%,1/16W,EMA CS28872FB01              PR144           
Q_RES_0402LF-8.87K,1%,1/16W,EMA CS28872FB01              PR145           
Q_RES_0402LF-8.87K,1%,1/16W,EMA CS28872FB01              PR150           
Q_RES_0402LF-8.87K,1%,1/16W,EMA CS28872FB01              PR151           
Q_RES_0402LF-8.87K,1%,1/16W,EMA CS28872FB01              PR224           
Q_RES_0402LF-8.87K,1%,1/16W,EMA CS28872FB01              PR225           
Q_RES_0402LF-8.87K,1%,1/16W,EMA CS28872FB01              PR285           
Q_RES_0402LF-8.87K,1%,1/16W,EMA CS28872FB01              PR286           
Q_RES_0402LF-8.87K,1%,1/16W,EMA CS28872FB01              PR291           
Q_RES_0402LF-8.87K,1%,1/16W,EMA CS28872FB01              PR292           
Q_RES_0402LF-8.87K,1%,1/16W,EMA CS28872FB01              PR297           
Q_RES_0402LF-8.87K,1%,1/16W,EMA CS28872FB01              PR298           
Q_RES_0402LF-8.87K,1%,1/16W,EMA CS28872FB01              PR325           
Q_RES_0402LF-8.87K,1%,1/16W,EMA CS28872FB01              PR326           
Q_RES_0402LF-8.87K,1%,1/16W,EMA CS28872FB01              PR353           
Q_RES_0402LF-8.87K,1%,1/16W,EMA CS28872FB01              PR354           
Q_RES_0402LF-8.87K,1%,1/16W,EMA CS28872FB01              PR1297          
Q_RES_0402LF-8.87K,1%,1/16W,EMA CS28872FB01              PR1298          
Q_RES_0402LF-8.87K,1%,1/16W,EMA CS28872FB01              PR1304          
Q_RES_0402LF-8.87K,1%,1/16W,EMA CS28872FB01              PR1305          
Q_RES_0402LF-8.87K,1%,1/16W,EMA CS28872FB01              PR1336          
Q_RES_0402LF-8.87K,1%,1/16W,EMA CS28872FB01              PR1707          
Q_RES_0402LF-8.87K,1%,1/16W,EMA CS28872FB01              PR1708          
Q_RES_0402LF-8.87K,1%,1/16W,EMA CS28872FB01              PR1709          
Q_RES_0402LF-8.87K,1%,1/16W,EMA CS28872FB01              PR1726          
Q_RES_0402LF-8.87K,1%,1/16W,EMA CS28872FB01              PR1727          
Q_RES_0402LF-8.87K,1%,1/16W,EMA CS28872FB01              PR1728          
Q_RES_0402LF-8.87K,1%,1/16W,EMA CS28872FB01              PR1746          
Q_RES_0402LF-8.87K,1%,1/16W,EMA CS28872FB01              PR2718          

----------------

Q_RES_0402LF-84.5K,1%,1/16W,CHA CS38452FB14              R31             
Q_RES_0402LF-84.5K,1%,1/16W,CHA CS38452FB14              R39             
Q_RES_0402LF-84.5K,1%,1/16W,CHA CS38452FB14              R47             
Q_RES_0402LF-84.5K,1%,1/16W,CHA CS38452FB14              R74             

----------------

Q_RES_0402LF-86.6K,1%,1/16W,CHA CS38662FB16              PR92            

----------------

Q_RES_0402LF-9.09K,1%,1/16W,CHA CS29092FB27              PR1303          
Q_RES_0402LF-9.09K,1%,1/16W,CHA CS29092FB27              PR2222          

----------------

Q_RES_0402LF-9.31K,1%,1/16W,CHA CS29312FB13              PR1339          

----------------

Q_RES_0603LF-1,1%,1/10W,CHIP,CA CS-1003F920              R442            
Q_RES_0603LF-1,1%,1/10W,CHIP,CA CS-1003F920              R447            
Q_RES_0603LF-1,1%,1/10W,CHIP,CA CS-1003F920              R519            

----------------

Q_RES_0603LF-10M,1%,1/10W,CHIPA CS61003F900              R120            

----------------

Q_RES_0603LF-2.2,1%,1/10W,CHIPA CS-2203F902              R571            
Q_RES_0603LF-2.2,1%,1/10W,CHIPA CS-2203F902              R572            

----------------

Q_RES_0603LF-200K,0.1%,1/10W,EA CS42003B901              R1316           

----------------

Q_RES_0805LF-0,5%,1/8W,CHIP,CSA CS00004JA40              R1747           

----------------

Q_RES_0805LF-0,5%,1/8W,EMPTY,CA CS00004JA40              R1765           

----------------

Q_RES_1206LF-0,,1/2W,CHIP,CS00A CS00007T200              R324            
Q_RES_1206LF-0,,1/2W,CHIP,CS00A CS00007T200              R330            

----------------

Q_RES_1206LF-0,,1/2W,EMPTY,CS0A CS00007T200              R323            
Q_RES_1206LF-0,,1/2W,EMPTY,CS0A CS00007T200              R329            

----------------

Q_RES_1206LF-0,5%,1/4W,CHIP,CSA CS00006J248              R511            
Q_RES_1206LF-0,5%,1/4W,CHIP,CSA CS00006J248              R513            

----------------

Q_RES_1206LF-0,5%,1/4W,EMPTY,CA CS00006J248              R512            
Q_RES_1206LF-0,5%,1/4W,EMPTY,CA CS00006J248              R514            

----------------

Q_RES_4P_12-0.001,1%,3W,SMLF,CA CS+001DFR00              R1837           
Q_RES_4P_12-0.001,1%,3W,SMLF,CA CS+001DFR00              R1838           

----------------

Q_RES_R0402LF-887,1%,1/16W,CHIA CS18872FB01              PR106           

----------------

Q_SHORT_SM-EMPTY,SHORT6 SHORT6                   PJ45            
Q_SHORT_SM-EMPTY,SHORT6 SHORT6                   PJ46            
Q_SHORT_SM-EMPTY,SHORT6 SHORT6                   PJ47            
Q_SHORT_SM-EMPTY,SHORT6 SHORT6                   PJ48            
Q_SHORT_SM-EMPTY,SHORT6 SHORT6                   PJ49            
Q_SHORT_SM-EMPTY,SHORT6 SHORT6                   PJ50            
Q_SHORT_SM-EMPTY,SHORT6 SHORT6                   PJ51            
Q_SHORT_SM-EMPTY,SHORT6 SHORT6                   PJ52            
Q_SHORT_SM-EMPTY,SHORT6 SHORT6                   PJ53            
Q_SHORT_SM-EMPTY,SHORT6 SHORT6                   PJ54            
Q_SHORT_SM-EMPTY,SHORT6 SHORT6                   PJ62            
Q_SHORT_SM-EMPTY,SHORT6 SHORT6                   PJ63            
Q_SHORT_SM-EMPTY,SHORT6 SHORT6                   PJ64            
Q_SHORT_SM-EMPTY,SHORT6 SHORT6                   PJ65            
Q_SHORT_SM-EMPTY,SHORT6 SHORT6                   PJ66            
Q_SHORT_SM-EMPTY,SHORT6 SHORT6                   PJ67            

----------------

Q_XTAL_4P_13BI_24GND-25MHZ,SMLA BG625000802              Y3              

----------------

Q_XTAL_4P_13_SMLF-25MHZ,IC,BG6A BG625000142              Y2              

----------------

RAA2213404GNPHB0-RAA2213404GNPA AL221340002              PU17            
RAA2213404GNPHB0-RAA2213404GNPA AL221340002              PU36            
RAA2213404GNPHB0-RAA2213404GNPA AL221340002              PU42            
RAA2213404GNPHB0-RAA2213404GNPA AL221340002              PU43_P0_1       
RAA2213404GNPHB0-RAA2213404GNPA AL221340002              PU44_P0_2       
RAA2213404GNPHB0-RAA2213404GNPA AL221340002              PU49            
RAA2213404GNPHB0-RAA2213404GNPA AL221340002              PU50_P1_1       
RAA2213404GNPHB0-RAA2213404GNPA AL221340002              PU51_P1_2       

----------------

RAA229126GNPHA0-RAA229126GNP#HA AL229126000              PU14            
RAA229126GNPHA0-RAA229126GNP#HA AL229126000              PU29            

----------------

RT9818C44GV-RT9818C-44GV,SMLF,A AL009818001              U99             

----------------

SCHOTTKY_AC-SX34F,SMLF,IC,BC00A BC00SX34Z01              D4              

----------------

SCONN140_G64V3431BHR-SCONN140_A DFHSE0FS038              J55             
SCONN140_G64V3431BHR-SCONN140_A DFHSE0FS038              J57             

----------------

SCONN140_G64V3431BHR-SCONN140_B DFHSE0FS038              J35             

----------------

SCONN168_623403212-SCONN168_6-A DFHSG8FS003              J37             
SCONN168_623403212-SCONN168_6-A DFHSG8FS003              J41             

----------------

SCONN280_ME1028040102011-SCONNA DFHST0FS008              J89             

----------------

SCONN288_ADR50001P003C01-SCONNA DFHST8FS301              J2              
SCONN288_ADR50001P003C01-SCONNA DFHST8FS301              J4              
SCONN288_ADR50001P003C01-SCONNA DFHST8FS301              J6              
SCONN288_ADR50001P003C01-SCONNA DFHST8FS301              J8              
SCONN288_ADR50001P003C01-SCONNA DFHST8FS301              J10             
SCONN288_ADR50001P003C01-SCONNA DFHST8FS301              J12             
SCONN288_ADR50001P003C01-SCONNA DFHST8FS301              J14             
SCONN288_ADR50001P003C01-SCONNA DFHST8FS301              J16             
SCONN288_ADR50001P003C01-SCONNA DFHST8FS301              J18             
SCONN288_ADR50001P003C01-SCONNA DFHST8FS301              J20             
SCONN288_ADR50001P003C01-SCONNA DFHST8FS301              J22             
SCONN288_ADR50001P003C01-SCONNA DFHST8FS301              J24             
SCONN288_ADR50001P003C01-SCONNA DFHST8FS301              J26             
SCONN288_ADR50001P003C01-SCONNA DFHST8FS301              J28             
SCONN288_ADR50001P003C01-SCONNA DFHST8FS301              J30             
SCONN288_ADR50001P003C01-SCONNA DFHST8FS301              J32             

----------------

SCONN288_ADR50001P013C01-SCONNA DFHST8FS302              J1              
SCONN288_ADR50001P013C01-SCONNA DFHST8FS302              J3              
SCONN288_ADR50001P013C01-SCONNA DFHST8FS302              J5              
SCONN288_ADR50001P013C01-SCONNA DFHST8FS302              J7              
SCONN288_ADR50001P013C01-SCONNA DFHST8FS302              J9              
SCONN288_ADR50001P013C01-SCONNA DFHST8FS302              J11             
SCONN288_ADR50001P013C01-SCONNA DFHST8FS302              J13             
SCONN288_ADR50001P013C01-SCONNA DFHST8FS302              J15             
SCONN288_ADR50001P013C01-SCONNA DFHST8FS302              J17             
SCONN288_ADR50001P013C01-SCONNA DFHST8FS302              J19             
SCONN288_ADR50001P013C01-SCONNA DFHST8FS302              J21             
SCONN288_ADR50001P013C01-SCONNA DFHST8FS302              J23             
SCONN288_ADR50001P013C01-SCONNA DFHST8FS302              J25             
SCONN288_ADR50001P013C01-SCONNA DFHST8FS302              J27             
SCONN288_ADR50001P013C01-SCONNA DFHST8FS302              J29             
SCONN288_ADR50001P013C01-SCONNA DFHST8FS302              J31             

----------------

SCONN60_QSH03001LDAKTR-SCONN60A DFHS60FS001              J42             

----------------

SCONN75K_APCI0155P004A-SCONN75A DFHS75FR313              J59             

----------------

SCONN84_123318136-SCONN84_1-23A DFHS84FS009              J33             
SCONN84_123318136-SCONN84_1-23A DFHS84FS009              J34             
SCONN84_123318136-SCONN84_1-23A DFHS84FS009              J61             
SCONN84_123318136-SCONN84_1-23A DFHS84FS009              J62             
SCONN84_123318136-SCONN84_1-23A DFHS84FS009              J87             
SCONN84_123318136-SCONN84_1-23A DFHS84FS009              J88             

----------------

SLG55221120010VTR-SLG55221-120A AL055221001              U79             

----------------

SN74LVC1G07DCKR-SN74LVC1G07DCKA AL1G0007016              U95             

----------------

SN74LVC1G08DBVR_SMLF-SN74LVC1GA AL1G0008012              U50             
SN74LVC1G08DBVR_SMLF-SN74LVC1GA AL1G0008012              U53             

----------------

SN74LVC1G17DCKR-SN74LVC1G17DCKA AL1G0017003              U75             
SN74LVC1G17DCKR-SN74LVC1G17DCKA AL1G0017003              U101            

----------------

SN74LVC2G07DCKR_SMLF-SN74LVC2GA AL002G07006              U58             
SN74LVC2G07DCKR_SMLF-SN74LVC2GA AL002G07006              U59             
SN74LVC2G07DCKR_SMLF-SN74LVC2GA AL002G07006              U134            
SN74LVC2G07DCKR_SMLF-SN74LVC2GA AL002G07006              U135            
SN74LVC2G07DCKR_SMLF-SN74LVC2GA AL002G07006              U136            
SN74LVC2G07DCKR_SMLF-SN74LVC2GA AL002G07006              U137            

----------------

SN74LVC2G17DCKR-SN74LVC2G17DCKA AL002G17001              U132            
SN74LVC2G17DCKR-SN74LVC2G17DCKA AL002G17001              U133            

----------------

SOCKET4677_AZIFS054P001C01-SOCA DGA^7000016              U1              
SOCKET4677_AZIFS054P001C01-SOCA DGA^7000016              U2              

----------------

SW8S_DHNF04FTVTR-SW8S_DHNF04FTA DHP00004F00              S1              
SW8S_DHNF04FTVTR-SW8S_DHNF04FTA DHP00004F00              S2              

----------------

TDR_3P_TH2-EMPTY,N_A N_A                      DB1             
TDR_3P_TH2-EMPTY,N_A N_A                      DB2             
TDR_3P_TH2-EMPTY,N_A N_A                      DB3             
TDR_3P_TH2-EMPTY,N_A N_A                      DB4             
TDR_3P_TH2-EMPTY,N_A N_A                      DB5             
TDR_3P_TH2-EMPTY,N_A N_A                      DB6             
TDR_3P_TH2-EMPTY,N_A N_A                      DB7             
TDR_3P_TH2-EMPTY,N_A N_A                      DB8             
TDR_3P_TH2-EMPTY,N_A N_A                      DB9             
TDR_3P_TH2-EMPTY,N_A N_A                      DB10            
TDR_3P_TH2-EMPTY,N_A N_A                      DB11            
TDR_3P_TH2-EMPTY,N_A N_A                      DB12            

----------------

TMP75AIDR-TMP75AIDR,SMLF,IC,ALA AL000075061              U63             
TMP75AIDR-TMP75AIDR,SMLF,IC,ALA AL000075061              U65             

----------------

TPS2553DBVR1-TPS2553DBVR-1,SMLA AL002553002              U27             

----------------

TPS259520DSGR-TPS259520DSGR,SMA AL259520000              U40             
TPS259520DSGR-TPS259520DSGR,SMA AL259520000              U56             
TPS259520DSGR-TPS259520DSGR,SMA AL259520000              U123            
TPS259520DSGR-TPS259520DSGR,SMA AL259520000              U124            
TPS259520DSGR-TPS259520DSGR,SMA AL259520000              U125            

----------------

TPS259540DSGR-TPS259540DSGR,SMA AL259540000              U126            
TPS259540DSGR-TPS259540DSGR,SMA AL259540000              U127            
TPS259540DSGR-TPS259540DSGR,SMA AL259540000              U128            
TPS259540DSGR-TPS259540DSGR,SMA AL259540000              U129            
TPS259540DSGR-TPS259540DSGR,SMA AL259540000              U138            

----------------

TPS259824ONRGER-TPS259824ONRGEA AL259824002              U57             

----------------

TPS3897PDRYR-TPS3897PDRYR,SMLFA AL003897006              U117            

----------------

TP_TDR_4P_FTS_TH-TP_TDR_4P_DIPA N_A                      X1              
TP_TDR_4P_FTS_TH-TP_TDR_4P_DIPA N_A                      X2              
TP_TDR_4P_FTS_TH-TP_TDR_4P_DIPA N_A                      X3              
TP_TDR_4P_FTS_TH-TP_TDR_4P_DIPA N_A                      X4              
TP_TDR_4P_FTS_TH-TP_TDR_4P_DIPA N_A                      X5              
TP_TDR_4P_FTS_TH-TP_TDR_4P_DIPA N_A                      X6              
TP_TDR_4P_FTS_TH-TP_TDR_4P_DIPA N_A                      X7              
TP_TDR_4P_FTS_TH-TP_TDR_4P_DIPA N_A                      X8              
TP_TDR_4P_FTS_TH-TP_TDR_4P_DIPA N_A                      X9              
TP_TDR_4P_FTS_TH-TP_TDR_4P_DIPA N_A                      X10             
TP_TDR_4P_FTS_TH-TP_TDR_4P_DIPA N_A                      X11             
TP_TDR_4P_FTS_TH-TP_TDR_4P_DIPA N_A                      X12             
TP_TDR_4P_FTS_TH-TP_TDR_4P_DIPA N_A                      X13             
TP_TDR_4P_FTS_TH-TP_TDR_4P_DIPA N_A                      X14             
TP_TDR_4P_FTS_TH-TP_TDR_4P_DIPA N_A                      X15             
TP_TDR_4P_FTS_TH-TP_TDR_4P_DIPA N_A                      X16             
TP_TDR_4P_FTS_TH-TP_TDR_4P_DIPA N_A                      X17             
TP_TDR_4P_FTS_TH-TP_TDR_4P_DIPA N_A                      X18             
TP_TDR_4P_FTS_TH-TP_TDR_4P_DIPA N_A                      X19             
TP_TDR_4P_FTS_TH-TP_TDR_4P_DIPA N_A                      X20             
TP_TDR_4P_FTS_TH-TP_TDR_4P_DIPA N_A                      X21             
TP_TDR_4P_FTS_TH-TP_TDR_4P_DIPA N_A                      X22             
TP_TDR_4P_FTS_TH-TP_TDR_4P_DIPA N_A                      X23             
TP_TDR_4P_FTS_TH-TP_TDR_4P_DIPA N_A                      X24             

----------------

TP_TP-NA,TP30    TP30                     J90_S1          
TP_TP-NA,TP30    TP30                     J90_S2          
TP_TP-NA,TP30    TP30                     J91_S1          
TP_TP-NA,TP30    TP30                     J91_S2          
TP_TP-NA,TP30    TP30                     J92_S1          
TP_TP-NA,TP30    TP30                     J92_S2          
TP_TP-NA,TP30    TP30                     J93_S1          
TP_TP-NA,TP30    TP30                     J93_S2          

----------------

TS3A24157RSER-TS3A24157RSER,SMA AL024157000              U96             
TS3A24157RSER-TS3A24157RSER,SMA AL024157000              U97             

----------------

END STUFF LIST
